FILE_TYPE = MACRO_DRAWING;
SET COLOR_WIRE YELLOW;
SET COLOR_PROP ORANGE;
SET COLOR_DOT WHITE;
SET COLOR_ARC YELLOW;
SET COLOR_BODY GREEN;
SET COLOR_NOTE PURPLE;
SET PROP_DISPLAY VALUE;
SET PAGE_NUMBER P184;
FORCEADD OFFPAGE..1
(-8850 3650);
FORCEPROP 2 LAST $XR0 80 
J 0
(-9071 3650);
DISPLAY 0.638298 (-9071 3650);
PAINT MONO (-9071 3650);
FORCEPROP 2 LAST CDS_LIB standard
J 0
(-8850 3650);
DISPLAY INVISIBLE (-8850 3650);
FORCEPROP 1 LAST OFFPAGE TRUE
J 0
(-8525 3525);
DISPLAY 0.872340 (-8525 3525);
PAINT GREEN (-8525 3525);
DISPLAY INVISIBLE (-8525 3525);
FORCEPROP 1 LAST COMMENT_BODY TRUE
J 0
(-8725 3550);
DISPLAY 0.872340 (-8725 3550);
PAINT GREEN (-8725 3550);
DISPLAY INVISIBLE (-8725 3550);
FORCEPROP 2 LAST PATH I1
J 0
(-8800 3725);
DISPLAY 1.021277 (-8800 3725);
DISPLAY INVISIBLE (-8800 3725);
FORCEADD Q_RES..2
(-7575 3050);
FORCEPROP 1 LAST LOCATION PR477
J 0
(-7530 3175);
DISPLAY 0.489362 (-7530 3175);
PAINT SKYBLUE (-7530 3175);
FORCEPROP 0 LAST $SEC 1
J 0
(-7525 3225);
DISPLAY 0.680851 (-7525 3225);
PAINT MONO (-7525 3225);
DISPLAY INVISIBLE (-7525 3225);
FORCEPROP 0 LAST CDS_SEC 1
J 0
(-7525 3225);
DISPLAY 1.021277 (-7525 3225);
DISPLAY INVISIBLE (-7525 3225);
FORCEPROP 1 LASTPIN (-7575 3150) $PN 1
J 0
(-7570 3112);
DISPLAY 0.489362 (-7570 3112);
PAINT MONO (-7570 3112);
FORCEPROP 1 LASTPIN (-7575 2950) $PN 2
J 0
(-7570 2960);
DISPLAY 0.489362 (-7570 2960);
PAINT MONO (-7570 2960);
FORCEPROP 1 LAST WATTAGE 1/16W
J 0
(-7535 3025);
DISPLAY 0.489362 (-7535 3025);
PAINT SKYBLUE (-7535 3025);
FORCEPROP 1 LAST MATERIAL CHIP
J 0
(-7535 2975);
DISPLAY 0.489362 (-7535 2975);
PAINT SKYBLUE (-7535 2975);
FORCEPROP 1 LAST TOLERANCE 5%
J 0
(-7530 3075);
DISPLAY 0.489362 (-7530 3075);
PAINT SKYBLUE (-7530 3075);
FORCEPROP 1 LAST VALUE 0
J 0
(-7530 3125);
DISPLAY 0.489362 (-7530 3125);
PAINT SKYBLUE (-7530 3125);
FORCEPROP 1 LAST PART_NUMBER CS00002JB38
J 0
(-7535 2925);
DISPLAY 0.489362 (-7535 2925);
PAINT SKYBLUE (-7535 2925);
FORCEPROP 1 LAST PACK_TYPE 0402LF
J 0
(-7535 2875);
DISPLAY 0.489362 (-7535 2875);
PAINT SKYBLUE (-7535 2875);
FORCEPROP 2 LAST CDS_LIB pure_quanta
J 0
(-7575 3050);
DISPLAY INVISIBLE (-7575 3050);
FORCEPROP 1 LAST PATH I10
J 0
(-7525 3225);
DISPLAY 0.978723 (-7525 3225);
PAINT WHITE (-7525 3225);
DISPLAY INVISIBLE (-7525 3225);
FORCEADD UNIVERSAL_POWER..1
(-7575 3250);
FORCEPROP 3 LASTPIN (-7575 3200) SIG_NAME P3V3_STBY\g
J 0
(-7565 3210);
DISPLAY 0.659574 (-7565 3210);
PAINT MONO (-7565 3210);
DISPLAY INVISIBLE (-7565 3210);
FORCEPROP 1 LAST HDL_POWER P3V3_STBY
J 1
(-7575 3300);
DISPLAY 0.489362 (-7575 3300);
PAINT GREEN (-7575 3300);
FORCEPROP 2 LAST CDS_LIB mstr_symbols
J 0
(-7575 3250);
PAINT MONO (-7575 3250);
DISPLAY INVISIBLE (-7575 3250);
FORCEPROP 1 LAST PATH I11
J 0
(-7525 3275);
DISPLAY 0.872340 (-7525 3275);
PAINT AQUA (-7525 3275);
DISPLAY INVISIBLE (-7525 3275);
FORCEADD Q_CAP..1
(-7575 4200);
FORCEPROP 1 LAST LOCATION PC254
J 0
(-7525 4300);
DISPLAY 0.489362 (-7525 4300);
PAINT SKYBLUE (-7525 4300);
FORCEPROP 0 LAST $SEC 1
J 0
(-7525 4325);
DISPLAY 0.680851 (-7525 4325);
PAINT MONO (-7525 4325);
DISPLAY INVISIBLE (-7525 4325);
FORCEPROP 0 LAST CDS_SEC 1
J 0
(-7525 4350);
DISPLAY 1.021277 (-7525 4350);
DISPLAY INVISIBLE (-7525 4350);
FORCEPROP 1 LASTPIN (-7575 4300) $PN 1
J 0
(-7565 4280);
DISPLAY 0.489362 (-7565 4280);
PAINT MONO (-7565 4280);
FORCEPROP 1 LASTPIN (-7575 4100) $PN 2
J 0
(-7565 4080);
DISPLAY 0.489362 (-7565 4080);
PAINT MONO (-7565 4080);
FORCEPROP 1 LAST MATERIAL X6S
J 0
(-7525 4100);
DISPLAY 0.489362 (-7525 4100);
PAINT SKYBLUE (-7525 4100);
FORCEPROP 1 LAST TOLERANCE 10%
J 0
(-7525 4150);
DISPLAY 0.489362 (-7525 4150);
PAINT SKYBLUE (-7525 4150);
FORCEPROP 1 LAST VALUE 10UF
J 0
(-7525 4250);
DISPLAY 0.489362 (-7525 4250);
PAINT SKYBLUE (-7525 4250);
FORCEPROP 1 LAST PART_NUMBER CH6104KEA00
J 0
(-7525 4050);
DISPLAY 0.489362 (-7525 4050);
PAINT SKYBLUE (-7525 4050);
FORCEPROP 1 LAST VOLTAGE 25V
J 0
(-7525 4200);
DISPLAY 0.489362 (-7525 4200);
PAINT SKYBLUE (-7525 4200);
FORCEPROP 1 LAST PACK_TYPE C0805
J 0
(-7525 4000);
DISPLAY 0.489362 (-7525 4000);
PAINT SKYBLUE (-7525 4000);
FORCEPROP 2 LAST CDS_LIB pure_quanta
J 0
(-7575 4200);
DISPLAY INVISIBLE (-7575 4200);
FORCEPROP 1 LAST PATH I12
J 0
(-7525 4350);
DISPLAY 0.978723 (-7525 4350);
PAINT WHITE (-7525 4350);
DISPLAY INVISIBLE (-7525 4350);
FORCEADD Q_CAP..1
(-7125 4200);
FORCEPROP 1 LAST LOCATION PC81
J 0
(-7075 4300);
DISPLAY 0.489362 (-7075 4300);
PAINT SKYBLUE (-7075 4300);
FORCEPROP 0 LAST $SEC 1
J 0
(-7075 4325);
DISPLAY 0.680851 (-7075 4325);
PAINT MONO (-7075 4325);
DISPLAY INVISIBLE (-7075 4325);
FORCEPROP 0 LAST CDS_SEC 1
J 0
(-7075 4350);
DISPLAY 0.680851 (-7075 4350);
DISPLAY INVISIBLE (-7075 4350);
FORCEPROP 1 LASTPIN (-7125 4300) $PN 1
J 0
(-7115 4280);
DISPLAY 0.489362 (-7115 4280);
PAINT MONO (-7115 4280);
FORCEPROP 1 LASTPIN (-7125 4100) $PN 2
J 0
(-7115 4080);
DISPLAY 0.489362 (-7115 4080);
PAINT MONO (-7115 4080);
FORCEPROP 1 LAST PART_NUMBER CH6104KEA00
J 0
(-7075 4050);
DISPLAY 0.489362 (-7075 4050);
PAINT SKYBLUE (-7075 4050);
FORCEPROP 1 LAST VALUE 10UF
J 0
(-7075 4250);
DISPLAY 0.489362 (-7075 4250);
PAINT SKYBLUE (-7075 4250);
FORCEPROP 1 LAST MATERIAL X6S
J 0
(-7075 4100);
DISPLAY 0.489362 (-7075 4100);
PAINT SKYBLUE (-7075 4100);
FORCEPROP 1 LAST TOLERANCE 10%
J 0
(-7075 4150);
DISPLAY 0.489362 (-7075 4150);
PAINT SKYBLUE (-7075 4150);
FORCEPROP 1 LAST VOLTAGE 25V
J 0
(-7075 4200);
DISPLAY 0.489362 (-7075 4200);
PAINT SKYBLUE (-7075 4200);
FORCEPROP 1 LAST PACK_TYPE C0805
J 0
(-7075 4000);
DISPLAY 0.489362 (-7075 4000);
PAINT SKYBLUE (-7075 4000);
FORCEPROP 2 LAST CDS_LIB pure_quanta
J 0
(-7125 4200);
DISPLAY INVISIBLE (-7125 4200);
FORCEPROP 1 LAST PATH I13
J 0
(-7075 4350);
DISPLAY 0.978723 (-7075 4350);
PAINT WHITE (-7075 4350);
DISPLAY INVISIBLE (-7075 4350);
FORCEADD Q_RES..2
(-6700 2625);
FORCEPROP 1 LAST LOCATION PR448
J 0
(-6655 2750);
DISPLAY 0.489362 (-6655 2750);
PAINT SKYBLUE (-6655 2750);
FORCEPROP 2 LAST SEC 1
J 0
(-6638 2868);
DISPLAY 0.680851 (-6638 2868);
PAINT MONO (-6638 2868);
DISPLAY INVISIBLE (-6638 2868);
FORCEPROP 1 LASTPIN (-6700 2725) $PN 1
J 0
(-6695 2687);
DISPLAY 0.489362 (-6695 2687);
FORCEPROP 1 LASTPIN (-6700 2525) $PN 2
J 0
(-6695 2535);
DISPLAY 0.489362 (-6695 2535);
FORCEPROP 1 LAST WATTAGE 1/16W
J 0
(-6660 2600);
DISPLAY 0.489362 (-6660 2600);
PAINT SKYBLUE (-6660 2600);
FORCEPROP 1 LAST MATERIAL CHIP
J 0
(-6660 2550);
DISPLAY 0.489362 (-6660 2550);
PAINT SKYBLUE (-6660 2550);
FORCEPROP 1 LAST TOLERANCE 1%
J 0
(-6655 2650);
DISPLAY 0.489362 (-6655 2650);
PAINT SKYBLUE (-6655 2650);
FORCEPROP 1 LAST VALUE 8.66K
J 0
(-6655 2700);
DISPLAY 0.489362 (-6655 2700);
PAINT SKYBLUE (-6655 2700);
FORCEPROP 1 LAST PART_NUMBER CS28662FB14
J 0
(-6660 2500);
DISPLAY 0.489362 (-6660 2500);
PAINT SKYBLUE (-6660 2500);
FORCEPROP 1 LAST PACK_TYPE 0402LF
J 0
(-6660 2450);
DISPLAY 0.489362 (-6660 2450);
PAINT SKYBLUE (-6660 2450);
FORCEPROP 2 LAST CDS_LIB pure_quanta
R 3
J 0
(-6700 2625);
DISPLAY INVISIBLE (-6700 2625);
FORCEPROP 2 LAST SEC_TYPE 0402LF
J 0
(-6638 2868);
DISPLAY 1.021277 (-6638 2868);
DISPLAY INVISIBLE (-6638 2868);
FORCEPROP 1 LAST PATH I14
J 0
(-6650 2800);
DISPLAY 0.978723 (-6650 2800);
PAINT WHITE (-6650 2800);
DISPLAY INVISIBLE (-6650 2800);
FORCEADD MPQ8633BGLEC838Z..1
(-5750 3475);
FORCEPROP 1 LAST LOCATION PU57
J 0
(-5997 4382);
DISPLAY 0.489362 (-5997 4382);
PAINT SKYBLUE (-5997 4382);
FORCEPROP 0 LAST $SEC 1
J 0
(-6000 4550);
DISPLAY 0.680851 (-6000 4550);
PAINT MONO (-6000 4550);
DISPLAY INVISIBLE (-6000 4550);
FORCEPROP 0 LAST CDS_SEC 1
J 0
(-6000 4550);
DISPLAY 1.021277 (-6000 4550);
DISPLAY INVISIBLE (-6000 4550);
FORCEPROP 0 LASTPIN (-5350 2800) $PN 2
J 0
(-5340 2810);
DISPLAY 0.489362 (-5340 2810);
PAINT MONO (-5340 2810);
FORCEPROP 0 LASTPIN (-5350 3950) $PN 1
J 0
(-5340 3960);
DISPLAY 0.489362 (-5340 3960);
PAINT MONO (-5340 3960);
FORCEPROP 0 LASTPIN (-6150 2850) $PN 3
J 2
(-6160 2860);
DISPLAY 0.489362 (-6160 2860);
PAINT MONO (-6160 2860);
FORCEPROP 0 LASTPIN (-6150 3650) $PN 8
J 2
(-6160 3660);
DISPLAY 0.489362 (-6160 3660);
PAINT MONO (-6160 3660);
FORCEPROP 0 LASTPIN (-5350 3200) $PN 7
J 0
(-5340 3210);
DISPLAY 0.489362 (-5340 3210);
PAINT MONO (-5340 3210);
FORCEPROP 0 LASTPIN (-6150 3450) $PN 4
J 2
(-6160 3460);
DISPLAY 0.489362 (-6160 3460);
PAINT MONO (-6160 3460);
FORCEPROP 0 LASTPIN (-5350 2850) $PN 11_18
J 0
(-5340 2860);
DISPLAY 0.489362 (-5340 2860);
PAINT MONO (-5340 2860);
FORCEPROP 0 LASTPIN (-5350 4150) $PN 9
J 0
(-5340 4160);
DISPLAY 0.489362 (-5340 4160);
PAINT MONO (-5340 4160);
FORCEPROP 0 LASTPIN (-5350 3050) $PN 6
J 0
(-5340 3060);
DISPLAY 0.489362 (-5340 3060);
PAINT MONO (-5340 3060);
FORCEPROP 0 LASTPIN (-5350 3650) $PN 20
J 0
(-5340 3660);
DISPLAY 0.489362 (-5340 3660);
PAINT MONO (-5340 3660);
FORCEPROP 0 LASTPIN (-5350 2950) $PN 5
J 0
(-5340 2960);
DISPLAY 0.489362 (-5340 2960);
PAINT MONO (-5340 2960);
FORCEPROP 0 LASTPIN (-6150 3200) $PN 19
J 2
(-6160 3210);
DISPLAY 0.489362 (-6160 3210);
PAINT MONO (-6160 3210);
FORCEPROP 0 LASTPIN (-6150 4150) $PN 10
J 2
(-6160 4160);
DISPLAY 0.489362 (-6160 4160);
PAINT MONO (-6160 4160);
FORCEPROP 0 LASTPIN (-6150 4100) $PN 21
J 2
(-6160 4110);
DISPLAY 0.489362 (-6160 4110);
PAINT MONO (-6160 4110);
FORCEPROP 2 LAST PART_TYPE SMLF
J 0
(-6000 4500);
DISPLAY 0.680851 (-6000 4500);
FORCEPROP 1 LAST MATERIAL IC
J 0
(-5997 4204);
DISPLAY 0.489362 (-5997 4204);
PAINT SKYBLUE (-5997 4204);
FORCEPROP 2 LAST VALUE MPQ8633BGLE-C838-Z
J 0
(-6000 4450);
DISPLAY 0.489362 (-6000 4450);
PAINT SKYBLUE (-6000 4450);
FORCEPROP 1 LAST PART_NUMBER AL008633005
J 0
(-5997 4283);
DISPLAY 0.489362 (-5997 4283);
PAINT SKYBLUE (-5997 4283);
FORCEPROP 2 LAST CDS_LIB pure_quanta
J 0
(-5750 3475);
DISPLAY INVISIBLE (-5750 3475);
FORCEPROP 1 LAST NEEDS_NO_SIZE TRUE
J 0
(-5750 3475);
DISPLAY 0.723404 (-5750 3475);
PAINT GREEN (-5750 3475);
DISPLAY INVISIBLE (-5750 3475);
FORCEPROP 1 LAST CDS_LMAN_SYM_OUTLINE -250,725,250,-725
J 0
(-5750 3475);
DISPLAY 0.468085 (-5750 3475);
PAINT GREEN (-5750 3475);
DISPLAY INVISIBLE (-5750 3475);
FORCEPROP 1 LAST PATH I15
J 0
(-5750 3475);
DISPLAY 0.723404 (-5750 3475);
PAINT GREEN (-5750 3475);
DISPLAY INVISIBLE (-5750 3475);
FORCEADD Q_CAP..1
(-6725 4200);
FORCEPROP 1 LAST LOCATION PC237
J 0
(-6675 4300);
DISPLAY 0.489362 (-6675 4300);
PAINT SKYBLUE (-6675 4300);
FORCEPROP 0 LAST $SEC 1
J 0
(-6675 4325);
DISPLAY 0.680851 (-6675 4325);
PAINT MONO (-6675 4325);
DISPLAY INVISIBLE (-6675 4325);
FORCEPROP 0 LAST CDS_SEC 1
J 0
(-6675 4325);
DISPLAY 1.021277 (-6675 4325);
DISPLAY INVISIBLE (-6675 4325);
FORCEPROP 1 LASTPIN (-6725 4300) $PN 1
J 0
(-6715 4280);
DISPLAY 0.489362 (-6715 4280);
PAINT MONO (-6715 4280);
FORCEPROP 1 LASTPIN (-6725 4100) $PN 2
J 0
(-6715 4080);
DISPLAY 0.489362 (-6715 4080);
PAINT MONO (-6715 4080);
FORCEPROP 1 LAST VOLTAGE 25V
J 0
(-6675 4200);
DISPLAY 0.489362 (-6675 4200);
PAINT SKYBLUE (-6675 4200);
FORCEPROP 1 LAST MATERIAL X7R
J 0
(-6675 4100);
DISPLAY 0.489362 (-6675 4100);
PAINT SKYBLUE (-6675 4100);
FORCEPROP 1 LAST TOLERANCE 10%
J 0
(-6675 4150);
DISPLAY 0.489362 (-6675 4150);
PAINT SKYBLUE (-6675 4150);
FORCEPROP 1 LAST VALUE 0.1UF
J 0
(-6675 4250);
DISPLAY 0.489362 (-6675 4250);
PAINT SKYBLUE (-6675 4250);
FORCEPROP 1 LAST PART_NUMBER CH4104K1B00
J 0
(-6675 4050);
DISPLAY 0.489362 (-6675 4050);
PAINT SKYBLUE (-6675 4050);
FORCEPROP 1 LAST PACK_TYPE 0402
J 0
(-6675 4000);
DISPLAY 0.489362 (-6675 4000);
PAINT SKYBLUE (-6675 4000);
FORCEPROP 2 LAST SIGNAL_MODEL DEFAULT_CAPACITOR_100000PF_2_1
J 0
(-6657 4470);
DISPLAY 1.021277 (-6657 4470);
DISPLAY INVISIBLE (-6657 4470);
FORCEPROP 2 LAST CDS_LIB pure_quanta
J 0
(-6725 4200);
PAINT MONO (-6725 4200);
DISPLAY INVISIBLE (-6725 4200);
FORCEPROP 1 LAST PATH I16
J 0
(-6675 4350);
DISPLAY 0.978723 (-6675 4350);
PAINT WHITE (-6675 4350);
DISPLAY INVISIBLE (-6675 4350);
FORCEPROP 2 LAST ROOM VR_CORE1_POWER_STAGE_1
J 1
(-6670 4326);
DISPLAY 1.021277 (-6670 4326);
PAINT RED (-6670 4326);
DISPLAY INVISIBLE (-6670 4326);
FORCEADD UNIVERSAL_GND..1
(-5125 2525);
FORCEPROP 3 LASTPIN (-5125 2575) SIG_NAME GND\g
J 0
(-5115 2585);
DISPLAY 0.659574 (-5115 2585);
PAINT MONO (-5115 2585);
DISPLAY INVISIBLE (-5115 2585);
FORCEPROP 2 LAST CDS_LIB pure_quanta_power
J 0
(-5125 2525);
DISPLAY INVISIBLE (-5125 2525);
FORCEPROP 1 LAST PATH I19
J 0
(-5050 2525);
DISPLAY 0.872340 (-5050 2525);
PAINT AQUA (-5050 2525);
DISPLAY INVISIBLE (-5050 2525);
FORCEPROP 1 LAST HDL_POWER GND
J 1
(-5100 2450);
DISPLAY 0.872340 (-5100 2450);
PAINT GREEN (-5100 2450);
DISPLAY INVISIBLE (-5100 2450);
FORCEADD Q_INDUCTOR..1
(-8875 4450);
FORCEPROP 1 LAST LOCATION PL77
J 0
(-9000 4610);
DISPLAY 0.489362 (-9000 4610);
PAINT SKYBLUE (-9000 4610);
FORCEPROP 0 LAST $SEC 1
J 0
(-9000 4750);
DISPLAY 0.680851 (-9000 4750);
PAINT MONO (-9000 4750);
DISPLAY INVISIBLE (-9000 4750);
FORCEPROP 0 LAST CDS_SEC 1
J 0
(-9000 4750);
DISPLAY 0.680851 (-9000 4750);
DISPLAY INVISIBLE (-9000 4750);
FORCEPROP 0 LASTPIN (-8975 4425) $PN 1
J 2
(-8985 4435);
DISPLAY 0.489362 (-8985 4435);
PAINT MONO (-8985 4435);
FORCEPROP 0 LASTPIN (-8775 4425) $PN 2
J 0
(-8765 4435);
DISPLAY 0.489362 (-8765 4435);
PAINT MONO (-8765 4435);
FORCEPROP 1 LAST MATERIAL IND
J 0
(-9000 4505);
DISPLAY 0.489362 (-9000 4505);
PAINT SKYBLUE (-9000 4505);
FORCEPROP 2 LAST VALUE BLM18SN220TN1D/8000MA
J 0
(-9000 4650);
DISPLAY 0.489362 (-9000 4650);
PAINT SKYBLUE (-9000 4650);
FORCEPROP 1 LAST PART_NUMBER CX220TN1001
J 0
(-9000 4560);
DISPLAY 0.489362 (-9000 4560);
PAINT SKYBLUE (-9000 4560);
FORCEPROP 2 LAST PACK_TYPE SMLF
J 0
(-9000 4700);
DISPLAY 0.489362 (-9000 4700);
PAINT SKYBLUE (-9000 4700);
FORCEPROP 2 LAST CDS_LIB pure_quanta
J 0
(-8875 4450);
DISPLAY INVISIBLE (-8875 4450);
FORCEPROP 1 LAST NEEDS_NO_SIZE TRUE
J 0
(-8875 4450);
DISPLAY 0.468085 (-8875 4450);
PAINT GREEN (-8875 4450);
DISPLAY INVISIBLE (-8875 4450);
FORCEPROP 1 LAST PATH I2
J 0
(-8800 4505);
DISPLAY 0.723404 (-8800 4505);
PAINT GREEN (-8800 4505);
DISPLAY INVISIBLE (-8800 4505);
FORCEADD UNIVERSAL_GND..1
(-5000 2525);
FORCEPROP 3 LASTPIN (-5000 2575) SIG_NAME GND\g
J 0
(-4990 2585);
DISPLAY 0.659574 (-4990 2585);
PAINT MONO (-4990 2585);
DISPLAY INVISIBLE (-4990 2585);
FORCEPROP 2 LAST CDS_LIB pure_quanta_power
J 0
(-5000 2525);
DISPLAY INVISIBLE (-5000 2525);
FORCEPROP 1 LAST PATH I20
J 0
(-4925 2525);
DISPLAY 0.872340 (-4925 2525);
PAINT AQUA (-4925 2525);
DISPLAY INVISIBLE (-4925 2525);
FORCEPROP 1 LAST HDL_POWER GND
J 1
(-4975 2450);
DISPLAY 0.872340 (-4975 2450);
PAINT GREEN (-4975 2450);
DISPLAY INVISIBLE (-4975 2450);
FORCEADD Q_CAP..1
(-5000 2775);
FORCEPROP 1 LAST LOCATION PC258
J 0
(-4950 2850);
DISPLAY 0.489362 (-4950 2850);
PAINT SKYBLUE (-4950 2850);
FORCEPROP 0 LAST $SEC 1
J 0
(-4950 2900);
DISPLAY 0.680851 (-4950 2900);
PAINT MONO (-4950 2900);
DISPLAY INVISIBLE (-4950 2900);
FORCEPROP 2 LAST CDS_SEC 1
J 0
(-4950 2975);
DISPLAY 0.680851 (-4950 2975);
DISPLAY INVISIBLE (-4950 2975);
FORCEPROP 1 LASTPIN (-5000 2875) $PN 1
J 0
(-4990 2855);
DISPLAY 0.489362 (-4990 2855);
PAINT MONO (-4990 2855);
FORCEPROP 1 LASTPIN (-5000 2675) $PN 2
J 0
(-4990 2655);
DISPLAY 0.489362 (-4990 2655);
PAINT MONO (-4990 2655);
FORCEPROP 1 LAST MATERIAL X7R
J 0
(-4950 2650);
DISPLAY 0.489362 (-4950 2650);
PAINT SKYBLUE (-4950 2650);
FORCEPROP 1 LAST TOLERANCE 10%
J 0
(-4950 2700);
DISPLAY 0.489362 (-4950 2700);
PAINT SKYBLUE (-4950 2700);
FORCEPROP 1 LAST VALUE 0.022UF
J 0
(-4950 2800);
DISPLAY 0.489362 (-4950 2800);
PAINT SKYBLUE (-4950 2800);
FORCEPROP 1 LAST PART_NUMBER CH3224K1B01
J 0
(-4950 2600);
DISPLAY 0.489362 (-4950 2600);
PAINT SKYBLUE (-4950 2600);
FORCEPROP 1 LAST VOLTAGE 25V
J 0
(-4950 2750);
DISPLAY 0.489362 (-4950 2750);
PAINT SKYBLUE (-4950 2750);
FORCEPROP 1 LAST PACK_TYPE 0402
J 0
(-4950 2550);
DISPLAY 0.489362 (-4950 2550);
PAINT SKYBLUE (-4950 2550);
FORCEPROP 2 LAST CDS_LIB pure_quanta
J 0
(-5000 2775);
DISPLAY INVISIBLE (-5000 2775);
FORCEPROP 1 LAST PATH I21
J 0
(-4950 2925);
DISPLAY 0.978723 (-4950 2925);
PAINT WHITE (-4950 2925);
DISPLAY INVISIBLE (-4950 2925);
FORCEADD Q_RES..2
(-4150 2675);
FORCEPROP 1 LAST LOCATION PR470
J 0
(-4105 2800);
DISPLAY 0.489362 (-4105 2800);
PAINT SKYBLUE (-4105 2800);
FORCEPROP 2 LAST $SEC 1
J 0
(-4100 2900);
DISPLAY 0.680851 (-4100 2900);
PAINT MONO (-4100 2900);
DISPLAY INVISIBLE (-4100 2900);
FORCEPROP 2 LAST CDS_SEC 1
J 0
(-4100 2900);
DISPLAY 0.680851 (-4100 2900);
DISPLAY INVISIBLE (-4100 2900);
FORCEPROP 1 LASTPIN (-4150 2775) $PN 1
J 0
(-4145 2737);
DISPLAY 0.489362 (-4145 2737);
FORCEPROP 1 LASTPIN (-4150 2575) $PN 2
J 0
(-4145 2585);
DISPLAY 0.489362 (-4145 2585);
FORCEPROP 1 LAST WATTAGE 1/16W
J 0
(-4110 2650);
DISPLAY 0.489362 (-4110 2650);
PAINT SKYBLUE (-4110 2650);
FORCEPROP 1 LAST MATERIAL CHIP
J 0
(-4110 2600);
DISPLAY 0.489362 (-4110 2600);
PAINT SKYBLUE (-4110 2600);
FORCEPROP 1 LAST TOLERANCE 1%
J 0
(-4105 2700);
DISPLAY 0.489362 (-4105 2700);
PAINT SKYBLUE (-4105 2700);
FORCEPROP 1 LAST VALUE 10K
J 0
(-4105 2750);
DISPLAY 0.489362 (-4105 2750);
PAINT SKYBLUE (-4105 2750);
FORCEPROP 1 LAST PART_NUMBER TMP_QCS31002FB26
J 0
(-4110 2550);
DISPLAY 0.489362 (-4110 2550);
PAINT SKYBLUE (-4110 2550);
FORCEPROP 1 LAST PACK_TYPE 0402LF
J 0
(-4110 2500);
DISPLAY 0.489362 (-4110 2500);
PAINT SKYBLUE (-4110 2500);
FORCEPROP 2 LAST CDS_LIB pure_quanta
J 0
(-4150 2675);
DISPLAY INVISIBLE (-4150 2675);
FORCEPROP 1 LAST PATH I22
J 0
(-4100 2850);
DISPLAY 0.978723 (-4100 2850);
PAINT WHITE (-4100 2850);
DISPLAY INVISIBLE (-4100 2850);
FORCEADD Q_RES..2
(-4700 4450);
FORCEPROP 1 LAST LOCATION PR465
J 0
(-4655 4575);
DISPLAY 0.489362 (-4655 4575);
PAINT SKYBLUE (-4655 4575);
FORCEPROP 2 LAST SEC 1
J 0
(-4649 4679);
DISPLAY 0.680851 (-4649 4679);
PAINT MONO (-4649 4679);
DISPLAY INVISIBLE (-4649 4679);
FORCEPROP 1 LASTPIN (-4700 4550) $PN 1
J 0
(-4695 4512);
DISPLAY 0.489362 (-4695 4512);
FORCEPROP 1 LASTPIN (-4700 4350) $PN 2
J 0
(-4695 4360);
DISPLAY 0.489362 (-4695 4360);
FORCEPROP 1 LAST WATTAGE 1/16W
J 0
(-4660 4425);
DISPLAY 0.489362 (-4660 4425);
PAINT SKYBLUE (-4660 4425);
FORCEPROP 1 LAST MATERIAL CHIP
J 0
(-4660 4375);
DISPLAY 0.489362 (-4660 4375);
PAINT SKYBLUE (-4660 4375);
FORCEPROP 1 LAST TOLERANCE 5%
J 0
(-4655 4475);
DISPLAY 0.489362 (-4655 4475);
PAINT SKYBLUE (-4655 4475);
FORCEPROP 1 LAST VALUE 10K
J 0
(-4655 4525);
DISPLAY 0.489362 (-4655 4525);
PAINT SKYBLUE (-4655 4525);
FORCEPROP 1 LAST PACK_TYPE 0402LF
J 0
(-4660 4275);
DISPLAY 0.489362 (-4660 4275);
PAINT SKYBLUE (-4660 4275);
FORCEPROP 1 LAST PART_NUMBER TMP_QCS31002JB28
J 0
(-4660 4325);
DISPLAY 0.489362 (-4660 4325);
PAINT SKYBLUE (-4660 4325);
FORCEPROP 2 LAST CDS_LIB pure_quanta
R 3
J 0
(-4700 4450);
PAINT MONO (-4700 4450);
DISPLAY INVISIBLE (-4700 4450);
FORCEPROP 2 LAST SEC_TYPE 0402LF
J 0
(-4649 4679);
DISPLAY 1.021277 (-4649 4679);
DISPLAY INVISIBLE (-4649 4679);
FORCEPROP 1 LAST PATH I23
J 0
(-4650 4625);
DISPLAY 0.978723 (-4650 4625);
PAINT WHITE (-4650 4625);
DISPLAY INVISIBLE (-4650 4625);
FORCEADD Q_CAP..1
(-4475 3800);
FORCEPROP 1 LAST LOCATION PC209
J 0
(-4425 3975);
DISPLAY 0.489362 (-4425 3975);
PAINT SKYBLUE (-4425 3975);
FORCEPROP 2 LAST SEC 1
J 0
(-4401 4019);
DISPLAY 0.680851 (-4401 4019);
PAINT MONO (-4401 4019);
DISPLAY INVISIBLE (-4401 4019);
FORCEPROP 1 LASTPIN (-4475 3900) $PN 1
J 0
(-4465 3880);
DISPLAY 0.489362 (-4465 3880);
FORCEPROP 1 LASTPIN (-4475 3700) $PN 2
J 0
(-4465 3680);
DISPLAY 0.489362 (-4465 3680);
FORCEPROP 1 LAST MATERIAL X7R
J 0
(-4425 3775);
DISPLAY 0.489362 (-4425 3775);
PAINT SKYBLUE (-4425 3775);
FORCEPROP 1 LAST TOLERANCE 10%
J 0
(-4425 3825);
DISPLAY 0.489362 (-4425 3825);
PAINT SKYBLUE (-4425 3825);
FORCEPROP 1 LAST VALUE 0.22UF
J 0
(-4425 3925);
DISPLAY 0.489362 (-4425 3925);
PAINT SKYBLUE (-4425 3925);
FORCEPROP 1 LAST PART_NUMBER CH4223K1B00
J 0
(-4425 3725);
DISPLAY 0.489362 (-4425 3725);
PAINT SKYBLUE (-4425 3725);
FORCEPROP 1 LAST VOLTAGE 16V
J 0
(-4425 3875);
DISPLAY 0.489362 (-4425 3875);
PAINT SKYBLUE (-4425 3875);
FORCEPROP 1 LAST PACK_TYPE 0402
J 0
(-4425 3675);
DISPLAY 0.489362 (-4425 3675);
PAINT SKYBLUE (-4425 3675);
FORCEPROP 2 LAST CDS_LIB pure_quanta
J 0
(-4475 3800);
PAINT MONO (-4475 3800);
DISPLAY INVISIBLE (-4475 3800);
FORCEPROP 2 LAST SEC_TYPE 0402
J 0
(-4401 4019);
DISPLAY 1.021277 (-4401 4019);
DISPLAY INVISIBLE (-4401 4019);
FORCEPROP 1 LAST PATH I24
J 0
(-4425 3950);
DISPLAY 0.978723 (-4425 3950);
PAINT WHITE (-4425 3950);
DISPLAY INVISIBLE (-4425 3950);
FORCEPROP 2 LAST ROOM VR_CORE1_POWER_STAGE_1
J 1
(-4420 3926);
DISPLAY 1.021277 (-4420 3926);
PAINT RED (-4420 3926);
DISPLAY INVISIBLE (-4420 3926);
FORCEADD UNIVERSAL_POWER..1
(-4700 4725);
FORCEPROP 3 LASTPIN (-4700 4675) SIG_NAME P3V3_STBY\g
J 0
(-4690 4685);
DISPLAY 0.659574 (-4690 4685);
PAINT MONO (-4690 4685);
DISPLAY INVISIBLE (-4690 4685);
FORCEPROP 1 LAST HDL_POWER P3V3_STBY
J 1
(-4700 4775);
DISPLAY 0.489362 (-4700 4775);
PAINT GREEN (-4700 4775);
FORCEPROP 2 LAST CDS_LIB mstr_symbols
J 0
(-4700 4725);
DISPLAY INVISIBLE (-4700 4725);
FORCEPROP 1 LAST PATH I25
J 0
(-4650 4750);
DISPLAY 0.872340 (-4650 4750);
PAINT AQUA (-4650 4750);
DISPLAY INVISIBLE (-4650 4750);
FORCEADD Q_CAP..2
(-3575 2875);
FORCEPROP 1 LAST LOCATION PC259
J 1
(-3575 2950);
DISPLAY 0.489362 (-3575 2950);
PAINT SKYBLUE (-3575 2950);
FORCEPROP 0 LAST $SEC 1
J 0
(-3575 3025);
DISPLAY 0.680851 (-3575 3025);
PAINT MONO (-3575 3025);
DISPLAY INVISIBLE (-3575 3025);
FORCEPROP 0 LAST CDS_SEC 1
J 0
(-3575 3025);
DISPLAY 0.680851 (-3575 3025);
DISPLAY INVISIBLE (-3575 3025);
FORCEPROP 1 LASTPIN (-3675 2875) $PN 1
J 0
(-3685 2890);
DISPLAY 0.489362 (-3685 2890);
PAINT MONO (-3685 2890);
FORCEPROP 1 LASTPIN (-3475 2875) $PN 2
J 0
(-3490 2890);
DISPLAY 0.489362 (-3490 2890);
PAINT MONO (-3490 2890);
FORCEPROP 1 LAST MATERIAL X7R
J 0
(-3500 2800);
DISPLAY 0.489362 (-3500 2800);
PAINT SKYBLUE (-3500 2800);
FORCEPROP 1 LAST TOLERANCE 10%
J 2
(-3700 2750);
DISPLAY 0.489362 (-3700 2750);
PAINT SKYBLUE (-3700 2750);
FORCEPROP 1 LAST VALUE 220PF
J 2
(-3650 2925);
DISPLAY 0.489362 (-3650 2925);
PAINT SKYBLUE (-3650 2925);
FORCEPROP 1 LAST PART_NUMBER TMP_QCH12206KB14
J 1
(-3775 2800);
DISPLAY 0.489362 (-3775 2800);
PAINT SKYBLUE (-3775 2800);
FORCEPROP 1 LAST VOLTAGE 50V
J 0
(-3475 2925);
DISPLAY 0.489362 (-3475 2925);
PAINT SKYBLUE (-3475 2925);
FORCEPROP 1 LAST PACK_TYPE 0402
J 1
(-3450 2750);
DISPLAY 0.489362 (-3450 2750);
PAINT SKYBLUE (-3450 2750);
FORCEPROP 2 LAST CDS_LIB pure_quanta
J 0
(-3575 2875);
DISPLAY INVISIBLE (-3575 2875);
FORCEPROP 1 LAST PATH I26
J 0
(-3575 3075);
DISPLAY 0.978723 (-3575 3075);
PAINT WHITE (-3575 3075);
DISPLAY INVISIBLE (-3575 3075);
FORCEADD Q_RES..1
(-3575 3200);
FORCEPROP 1 LAST LOCATION PR471
J 0
(-3625 3250);
DISPLAY 0.489362 (-3625 3250);
PAINT SKYBLUE (-3625 3250);
FORCEPROP 2 LAST $SEC 1
J 0
(-3602 3413);
DISPLAY 0.680851 (-3602 3413);
PAINT MONO (-3602 3413);
DISPLAY INVISIBLE (-3602 3413);
FORCEPROP 2 LAST CDS_SEC 1
J 0
(-3602 3413);
DISPLAY 0.680851 (-3602 3413);
DISPLAY INVISIBLE (-3602 3413);
FORCEPROP 1 LASTPIN (-3675 3200) $PN 1
J 0
(-3663 3212);
DISPLAY 0.489362 (-3663 3212);
FORCEPROP 1 LASTPIN (-3475 3200) $PN 2
J 0
(-3513 3212);
DISPLAY 0.489362 (-3513 3212);
FORCEPROP 1 LAST MATERIAL CHIP
J 0
(-3400 3250);
DISPLAY 0.489362 (-3400 3250);
PAINT SKYBLUE (-3400 3250);
FORCEPROP 1 LAST VALUE 20K
J 2
(-3700 3250);
DISPLAY 0.489362 (-3700 3250);
PAINT SKYBLUE (-3700 3250);
FORCEPROP 1 LAST PART_NUMBER CS32002FB29
J 0
(-3825 3150);
DISPLAY 0.489362 (-3825 3150);
PAINT SKYBLUE (-3825 3150);
FORCEPROP 1 LAST PACK_TYPE 0402LF
J 0
(-3400 3150);
DISPLAY 0.489362 (-3400 3150);
PAINT SKYBLUE (-3400 3150);
FORCEPROP 2 LAST CDS_LIB pure_quanta
J 0
(-3575 3200);
DISPLAY INVISIBLE (-3575 3200);
FORCEPROP 1 LAST PATH I27
J 0
(-3625 3350);
DISPLAY 0.978723 (-3625 3350);
PAINT WHITE (-3625 3350);
DISPLAY INVISIBLE (-3625 3350);
FORCEPROP 1 LAST WATTAGE 1/16W
J 2
(-3001 3218);
DISPLAY 0.978723 (-3001 3218);
PAINT SKYBLUE (-3001 3218);
DISPLAY INVISIBLE (-3001 3218);
FORCEPROP 1 LAST TOLERANCE 1%
J 0
(-3455 3219);
DISPLAY 0.978723 (-3455 3219);
PAINT SKYBLUE (-3455 3219);
DISPLAY INVISIBLE (-3455 3219);
FORCEADD Q_INDUCTOR..1
(-3575 3675);
FORCEPROP 1 LAST LOCATION PL78
J 0
(-3700 3835);
DISPLAY 0.489362 (-3700 3835);
PAINT SKYBLUE (-3700 3835);
FORCEPROP 2 LAST $SEC 1
J 0
(-3700 3975);
DISPLAY 0.680851 (-3700 3975);
PAINT MONO (-3700 3975);
DISPLAY INVISIBLE (-3700 3975);
FORCEPROP 2 LAST CDS_SEC 1
J 0
(-3700 3975);
DISPLAY 0.680851 (-3700 3975);
DISPLAY INVISIBLE (-3700 3975);
FORCEPROP 2 LASTPIN (-3675 3650) $PN 1
J 2
(-3685 3660);
DISPLAY 0.489362 (-3685 3660);
FORCEPROP 2 LASTPIN (-3475 3650) $PN 2
J 0
(-3465 3660);
DISPLAY 0.489362 (-3465 3660);
FORCEPROP 1 LAST MATERIAL IND
J 0
(-3700 3730);
DISPLAY 0.489362 (-3700 3730);
PAINT SKYBLUE (-3700 3730);
FORCEPROP 2 LAST VALUE 1UH
J 0
(-3700 3875);
DISPLAY 0.489362 (-3700 3875);
PAINT SKYBLUE (-3700 3875);
FORCEPROP 2 LAST PACK_TYPE SMLF
J 0
(-3700 3925);
DISPLAY 0.489362 (-3700 3925);
PAINT SKYBLUE (-3700 3925);
FORCEPROP 1 LAST PART_NUMBER CV-10B0MZ13
J 0
(-3700 3785);
DISPLAY 0.489362 (-3700 3785);
PAINT SKYBLUE (-3700 3785);
FORCEPROP 2 LAST CDS_LIB pure_quanta
J 0
(-3575 3675);
DISPLAY INVISIBLE (-3575 3675);
FORCEPROP 1 LAST NEEDS_NO_SIZE TRUE
J 0
(-3575 3675);
DISPLAY 0.468085 (-3575 3675);
PAINT GREEN (-3575 3675);
DISPLAY INVISIBLE (-3575 3675);
FORCEPROP 1 LAST PATH I28
J 0
(-3500 3730);
DISPLAY 0.723404 (-3500 3730);
PAINT GREEN (-3500 3730);
DISPLAY INVISIBLE (-3500 3730);
FORCEADD Q_CAP..1
(-2275 3400);
FORCEPROP 1 LAST LOCATION PC288
J 0
(-2225 3500);
DISPLAY 0.489362 (-2225 3500);
PAINT SKYBLUE (-2225 3500);
FORCEPROP 0 LAST $SEC 1
J 0
(-2225 3550);
DISPLAY 0.680851 (-2225 3550);
PAINT MONO (-2225 3550);
DISPLAY INVISIBLE (-2225 3550);
FORCEPROP 0 LAST CDS_SEC 1
J 0
(-2225 3550);
DISPLAY 1.021277 (-2225 3550);
DISPLAY INVISIBLE (-2225 3550);
FORCEPROP 1 LASTPIN (-2275 3500) $PN 1
J 0
(-2265 3480);
DISPLAY 0.489362 (-2265 3480);
PAINT MONO (-2265 3480);
FORCEPROP 1 LASTPIN (-2275 3300) $PN 2
J 0
(-2265 3280);
DISPLAY 0.489362 (-2265 3280);
PAINT MONO (-2265 3280);
FORCEPROP 1 LAST MATERIAL X6S
J 0
(-2225 3300);
DISPLAY 0.489362 (-2225 3300);
PAINT SKYBLUE (-2225 3300);
FORCEPROP 1 LAST TOLERANCE 20%
J 0
(-2225 3350);
DISPLAY 0.489362 (-2225 3350);
PAINT SKYBLUE (-2225 3350);
FORCEPROP 1 LAST VALUE 22UF
J 0
(-2225 3450);
DISPLAY 0.489362 (-2225 3450);
PAINT SKYBLUE (-2225 3450);
FORCEPROP 1 LAST VOLTAGE 4V
J 0
(-2225 3400);
DISPLAY 0.489362 (-2225 3400);
PAINT SKYBLUE (-2225 3400);
FORCEPROP 1 LAST PACK_TYPE 0805
J 0
(-2225 3250);
DISPLAY 0.489362 (-2225 3250);
PAINT SKYBLUE (-2225 3250);
FORCEPROP 2 LAST CDS_LIB pure_quanta
J 0
(-2275 3400);
DISPLAY INVISIBLE (-2275 3400);
FORCEPROP 1 LAST PATH I31
J 0
(-2225 3550);
DISPLAY 0.978723 (-2225 3550);
PAINT WHITE (-2225 3550);
DISPLAY INVISIBLE (-2225 3550);
FORCEPROP 1 LAST PART_NUMBER TMP_QCH622KMEA01
J 0
(-2225 3250);
DISPLAY 0.489362 (-2225 3250);
PAINT SKYBLUE (-2225 3250);
DISPLAY INVISIBLE (-2225 3250);
FORCEADD Q_CAP..1
(-2025 3400);
FORCEPROP 1 LAST LOCATION PC260
J 0
(-1975 3500);
DISPLAY 0.489362 (-1975 3500);
PAINT SKYBLUE (-1975 3500);
FORCEPROP 0 LAST $SEC 1
J 0
(-1975 3550);
DISPLAY 0.680851 (-1975 3550);
PAINT MONO (-1975 3550);
DISPLAY INVISIBLE (-1975 3550);
FORCEPROP 0 LAST CDS_SEC 1
J 0
(-1975 3550);
DISPLAY 0.680851 (-1975 3550);
DISPLAY INVISIBLE (-1975 3550);
FORCEPROP 1 LASTPIN (-2025 3500) $PN 1
J 0
(-2015 3480);
DISPLAY 0.489362 (-2015 3480);
PAINT MONO (-2015 3480);
FORCEPROP 1 LASTPIN (-2025 3300) $PN 2
J 0
(-2015 3280);
DISPLAY 0.489362 (-2015 3280);
PAINT MONO (-2015 3280);
FORCEPROP 1 LAST MATERIAL EMPTY
J 0
(-1975 3300);
DISPLAY 0.489362 (-1975 3300);
PAINT RED (-1975 3300);
FORCEPROP 1 LAST TOLERANCE 20%
J 0
(-1975 3350);
DISPLAY 0.489362 (-1975 3350);
PAINT SKYBLUE (-1975 3350);
FORCEPROP 1 LAST VALUE 22UF
J 0
(-1975 3450);
DISPLAY 0.489362 (-1975 3450);
PAINT SKYBLUE (-1975 3450);
FORCEPROP 1 LAST VOLTAGE 4V
J 0
(-1975 3400);
DISPLAY 0.489362 (-1975 3400);
PAINT SKYBLUE (-1975 3400);
FORCEPROP 1 LAST PACK_TYPE 0805
J 0
(-1975 3250);
DISPLAY 0.489362 (-1975 3250);
PAINT SKYBLUE (-1975 3250);
FORCEPROP 2 LAST CDS_LIB pure_quanta
J 0
(-2025 3400);
DISPLAY INVISIBLE (-2025 3400);
FORCEPROP 1 LAST PATH I32
J 0
(-1975 3550);
DISPLAY 0.978723 (-1975 3550);
PAINT WHITE (-1975 3550);
DISPLAY INVISIBLE (-1975 3550);
FORCEPROP 1 LAST PART_NUMBER TMP_QCH622KMEA01
J 0
(-1975 3250);
DISPLAY 0.489362 (-1975 3250);
PAINT SKYBLUE (-1975 3250);
DISPLAY INVISIBLE (-1975 3250);
FORCEADD Q_CAP..1
(-1700 3400);
FORCEPROP 1 LAST LOCATION PC261
J 0
(-1650 3500);
DISPLAY 0.489362 (-1650 3500);
PAINT SKYBLUE (-1650 3500);
FORCEPROP 0 LAST $SEC 1
J 0
(-1650 3550);
DISPLAY 0.680851 (-1650 3550);
PAINT MONO (-1650 3550);
DISPLAY INVISIBLE (-1650 3550);
FORCEPROP 0 LAST CDS_SEC 1
J 0
(-1650 3550);
DISPLAY 0.680851 (-1650 3550);
DISPLAY INVISIBLE (-1650 3550);
FORCEPROP 1 LASTPIN (-1700 3500) $PN 1
J 0
(-1690 3480);
DISPLAY 0.489362 (-1690 3480);
PAINT MONO (-1690 3480);
FORCEPROP 1 LASTPIN (-1700 3300) $PN 2
J 0
(-1690 3280);
DISPLAY 0.489362 (-1690 3280);
PAINT MONO (-1690 3280);
FORCEPROP 1 LAST MATERIAL EMPTY
J 0
(-1650 3300);
DISPLAY 0.489362 (-1650 3300);
PAINT RED (-1650 3300);
FORCEPROP 1 LAST TOLERANCE 20%
J 0
(-1650 3350);
DISPLAY 0.489362 (-1650 3350);
PAINT SKYBLUE (-1650 3350);
FORCEPROP 1 LAST VALUE 22UF
J 0
(-1650 3450);
DISPLAY 0.489362 (-1650 3450);
PAINT SKYBLUE (-1650 3450);
FORCEPROP 1 LAST VOLTAGE 4V
J 0
(-1650 3400);
DISPLAY 0.489362 (-1650 3400);
PAINT SKYBLUE (-1650 3400);
FORCEPROP 1 LAST PACK_TYPE 0805
J 0
(-1650 3250);
DISPLAY 0.489362 (-1650 3250);
PAINT SKYBLUE (-1650 3250);
FORCEPROP 2 LAST CDS_LIB pure_quanta
J 0
(-1700 3400);
DISPLAY INVISIBLE (-1700 3400);
FORCEPROP 1 LAST PATH I33
J 0
(-1650 3550);
DISPLAY 0.978723 (-1650 3550);
PAINT WHITE (-1650 3550);
DISPLAY INVISIBLE (-1650 3550);
FORCEPROP 1 LAST PART_NUMBER TMP_QCH622KMEA01
J 0
(-1650 3250);
DISPLAY 0.489362 (-1650 3250);
PAINT SKYBLUE (-1650 3250);
DISPLAY INVISIBLE (-1650 3250);
FORCEADD UNIVERSAL_GND..1
(-500 2850);
FORCEPROP 3 LASTPIN (-500 2900) SIG_NAME GND\g
J 0
(-490 2910);
DISPLAY 0.659574 (-490 2910);
PAINT MONO (-490 2910);
DISPLAY INVISIBLE (-490 2910);
FORCEPROP 2 LAST CDS_LIB pure_quanta_power
J 0
(-500 2850);
DISPLAY INVISIBLE (-500 2850);
FORCEPROP 1 LAST PATH I34
J 0
(-425 2850);
DISPLAY 0.872340 (-425 2850);
PAINT AQUA (-425 2850);
DISPLAY INVISIBLE (-425 2850);
FORCEPROP 1 LAST HDL_POWER GND
J 1
(-475 2775);
DISPLAY 0.872340 (-475 2775);
PAINT GREEN (-475 2775);
DISPLAY INVISIBLE (-475 2775);
FORCEADD P1V0..1
(-500 4025);
FORCEPROP 3 LASTPIN (-500 3975) SIG_NAME PVDD18_S5_P0\g
J 0
(-490 3985);
DISPLAY 0.659574 (-490 3985);
PAINT MONO (-490 3985);
DISPLAY INVISIBLE (-490 3985);
FORCEPROP 1 LAST HDL_POWER PVDD18_S5_P0
J 1
(-500 4075);
DISPLAY 0.489362 (-500 4075);
PAINT GREEN (-500 4075);
FORCEPROP 2 LAST CDS_LIB pure_quanta_power
J 0
(-500 4025);
PAINT MONO (-500 4025);
DISPLAY INVISIBLE (-500 4025);
FORCEPROP 1 LAST PATH I36
J 0
(-450 4050);
DISPLAY 0.872340 (-450 4050);
PAINT AQUA (-450 4050);
DISPLAY INVISIBLE (-450 4050);
FORCEADD Q_RES..1
(-2600 2400);
FORCEPROP 1 LAST LOCATION PR434
J 0
(-2600 2450);
DISPLAY 0.489362 (-2600 2450);
PAINT SKYBLUE (-2600 2450);
FORCEPROP 0 LAST $SEC 1
J 0
(-2600 2475);
DISPLAY 0.680851 (-2600 2475);
PAINT MONO (-2600 2475);
DISPLAY INVISIBLE (-2600 2475);
FORCEPROP 0 LAST CDS_SEC 1
J 0
(-2600 2475);
DISPLAY 1.021277 (-2600 2475);
DISPLAY INVISIBLE (-2600 2475);
FORCEPROP 1 LASTPIN (-2700 2400) $PN 1
J 0
(-2688 2412);
DISPLAY 0.489362 (-2688 2412);
PAINT MONO (-2688 2412);
FORCEPROP 1 LASTPIN (-2500 2400) $PN 2
J 0
(-2538 2412);
DISPLAY 0.489362 (-2538 2412);
PAINT MONO (-2538 2412);
FORCEPROP 1 LAST WATTAGE 1/16W
J 2
(-2300 2300);
DISPLAY 0.489362 (-2300 2300);
PAINT SKYBLUE (-2300 2300);
FORCEPROP 1 LAST MATERIAL CHIP
J 0
(-2400 2425);
DISPLAY 0.489362 (-2400 2425);
PAINT SKYBLUE (-2400 2425);
FORCEPROP 1 LAST TOLERANCE 1%
J 0
(-2775 2300);
DISPLAY 0.489362 (-2775 2300);
PAINT SKYBLUE (-2775 2300);
FORCEPROP 1 LAST VALUE 10
J 2
(-2725 2425);
DISPLAY 0.489362 (-2725 2425);
PAINT SKYBLUE (-2725 2425);
FORCEPROP 1 LAST PART_NUMBER CS01002FB07
J 0
(-2875 2350);
DISPLAY 0.489362 (-2875 2350);
PAINT SKYBLUE (-2875 2350);
FORCEPROP 1 LAST PACK_TYPE 0402LF
J 0
(-2425 2350);
DISPLAY 0.489362 (-2425 2350);
PAINT SKYBLUE (-2425 2350);
FORCEPROP 2 LAST CDS_LIB pure_quanta
J 0
(-2600 2400);
DISPLAY INVISIBLE (-2600 2400);
FORCEPROP 1 LAST PATH I38
J 0
(-2650 2550);
DISPLAY 0.978723 (-2650 2550);
PAINT WHITE (-2650 2550);
DISPLAY INVISIBLE (-2650 2550);
FORCEADD Q_RES..2
R 1
(-2600 2100);
FORCEPROP 1 LAST LOCATION PR435
J 0
(-2600 2150);
DISPLAY 0.489362 (-2600 2150);
PAINT SKYBLUE (-2600 2150);
FORCEPROP 0 LAST $SEC 1
R 1
J 0
(-2475 2175);
DISPLAY 0.680851 (-2475 2175);
PAINT MONO (-2475 2175);
DISPLAY INVISIBLE (-2475 2175);
FORCEPROP 0 LAST CDS_SEC 1
R 1
J 0
(-2475 2175);
DISPLAY 1.021277 (-2475 2175);
DISPLAY INVISIBLE (-2475 2175);
FORCEPROP 1 LASTPIN (-2700 2100) $PN 1
R 1
J 0
(-2662 2105);
DISPLAY 0.489362 (-2662 2105);
PAINT MONO (-2662 2105);
FORCEPROP 1 LASTPIN (-2500 2100) $PN 2
R 1
J 0
(-2510 2105);
DISPLAY 0.489362 (-2510 2105);
PAINT MONO (-2510 2105);
FORCEPROP 1 LAST WATTAGE 1/16W
J 0
(-2500 2000);
DISPLAY 0.489362 (-2500 2000);
PAINT SKYBLUE (-2500 2000);
FORCEPROP 1 LAST MATERIAL CHIP
J 0
(-2475 2150);
DISPLAY 0.489362 (-2475 2150);
PAINT SKYBLUE (-2475 2150);
FORCEPROP 1 LAST TOLERANCE 5%
J 0
(-2775 2000);
DISPLAY 0.489362 (-2775 2000);
PAINT SKYBLUE (-2775 2000);
FORCEPROP 1 LAST VALUE 0
R 2
J 0
(-2750 2150);
DISPLAY 0.489362 (-2750 2150);
PAINT SKYBLUE (-2750 2150);
FORCEPROP 1 LAST PART_NUMBER CS00002JB38
J 0
(-2925 2050);
DISPLAY 0.489362 (-2925 2050);
PAINT SKYBLUE (-2925 2050);
FORCEPROP 1 LAST PACK_TYPE 0402LF
J 0
(-2500 2050);
DISPLAY 0.489362 (-2500 2050);
PAINT SKYBLUE (-2500 2050);
FORCEPROP 2 LAST CDS_LIB pure_quanta
J 0
(-2600 2100);
DISPLAY INVISIBLE (-2600 2100);
FORCEPROP 1 LAST PATH I39
R 1
J 0
(-2775 2150);
DISPLAY 0.978723 (-2775 2150);
PAINT WHITE (-2775 2150);
DISPLAY INVISIBLE (-2775 2150);
FORCEADD OFFPAGE..1
R 2
(-1400 2100);
FORCEPROP 2 LAST $XR0 27 
J 0
(-1124 2100);
DISPLAY 0.638298 (-1124 2100);
PAINT MONO (-1124 2100);
FORCEPROP 2 LAST CDS_LIB standard
J 0
(-1400 2100);
DISPLAY INVISIBLE (-1400 2100);
FORCEPROP 1 LAST OFFPAGE TRUE
J 2
(-1725 1975);
DISPLAY 0.872340 (-1725 1975);
PAINT GREEN (-1725 1975);
DISPLAY INVISIBLE (-1725 1975);
FORCEPROP 1 LAST COMMENT_BODY TRUE
J 2
(-1525 2000);
DISPLAY 0.872340 (-1525 2000);
PAINT GREEN (-1525 2000);
DISPLAY INVISIBLE (-1525 2000);
FORCEPROP 2 LAST PATH I40
J 0
(-1225 2175);
DISPLAY 1.021277 (-1225 2175);
DISPLAY INVISIBLE (-1225 2175);
FORCEADD OFFPAGE..1
R 2
(-1400 2400);
FORCEPROP 2 LAST $XR0 27 
J 0
(-1124 2400);
DISPLAY 0.638298 (-1124 2400);
PAINT MONO (-1124 2400);
FORCEPROP 2 LAST CDS_LIB standard
J 0
(-1400 2400);
DISPLAY INVISIBLE (-1400 2400);
FORCEPROP 1 LAST OFFPAGE TRUE
J 2
(-1725 2275);
DISPLAY 0.872340 (-1725 2275);
PAINT GREEN (-1725 2275);
DISPLAY INVISIBLE (-1725 2275);
FORCEPROP 1 LAST COMMENT_BODY TRUE
J 2
(-1525 2300);
DISPLAY 0.872340 (-1525 2300);
PAINT GREEN (-1525 2300);
DISPLAY INVISIBLE (-1525 2300);
FORCEPROP 2 LAST PATH I41
J 0
(-1225 2475);
DISPLAY 1.021277 (-1225 2475);
DISPLAY INVISIBLE (-1225 2475);
FORCEADD Q_RES..1
R 1
(-3575 1850);
FORCEPROP 1 LAST LOCATION PR418
J 0
(-3525 2025);
DISPLAY 0.489362 (-3525 2025);
PAINT SKYBLUE (-3525 2025);
FORCEPROP 0 LAST $SEC 1
R 1
J 0
(-3525 2050);
DISPLAY 0.680851 (-3525 2050);
PAINT MONO (-3525 2050);
DISPLAY INVISIBLE (-3525 2050);
FORCEPROP 0 LAST CDS_SEC 1
R 1
J 0
(-3525 2050);
DISPLAY 1.021277 (-3525 2050);
DISPLAY INVISIBLE (-3525 2050);
FORCEPROP 1 LASTPIN (-3575 1750) $PN 1
R 1
J 0
(-3587 1762);
DISPLAY 0.489362 (-3587 1762);
PAINT MONO (-3587 1762);
FORCEPROP 1 LASTPIN (-3575 1950) $PN 2
R 1
J 0
(-3587 1912);
DISPLAY 0.489362 (-3587 1912);
PAINT MONO (-3587 1912);
FORCEPROP 1 LAST WATTAGE 1/16W
J 0
(-3525 1875);
DISPLAY 0.489362 (-3525 1875);
PAINT SKYBLUE (-3525 1875);
FORCEPROP 1 LAST MATERIAL CHIP
J 0
(-3525 1825);
DISPLAY 0.489362 (-3525 1825);
PAINT SKYBLUE (-3525 1825);
FORCEPROP 1 LAST TOLERANCE 1%
J 0
(-3525 1925);
DISPLAY 0.489362 (-3525 1925);
PAINT SKYBLUE (-3525 1925);
FORCEPROP 1 LAST VALUE 49.9
J 0
(-3525 1975);
DISPLAY 0.489362 (-3525 1975);
PAINT SKYBLUE (-3525 1975);
FORCEPROP 1 LAST PART_NUMBER CS04992FB07
J 0
(-3525 1775);
DISPLAY 0.489362 (-3525 1775);
PAINT SKYBLUE (-3525 1775);
FORCEPROP 1 LAST PACK_TYPE 0402LF
J 0
(-3525 1725);
DISPLAY 0.489362 (-3525 1725);
PAINT SKYBLUE (-3525 1725);
FORCEPROP 2 LAST CDS_LIB pure_quanta
J 0
(-3575 1850);
DISPLAY INVISIBLE (-3575 1850);
FORCEPROP 1 LAST PATH I42
R 1
J 0
(-3725 1800);
DISPLAY 0.978723 (-3725 1800);
PAINT WHITE (-3725 1800);
DISPLAY INVISIBLE (-3725 1800);
FORCEADD UNIVERSAL_GND..1
(-3575 1600);
FORCEPROP 3 LASTPIN (-3575 1650) SIG_NAME GND\g
J 0
(-3565 1660);
DISPLAY 0.659574 (-3565 1660);
PAINT MONO (-3565 1660);
DISPLAY INVISIBLE (-3565 1660);
FORCEPROP 2 LAST CDS_LIB pure_quanta_power
J 0
(-3575 1600);
DISPLAY INVISIBLE (-3575 1600);
FORCEPROP 1 LAST PATH I43
J 0
(-3500 1600);
DISPLAY 0.872340 (-3500 1600);
PAINT AQUA (-3500 1600);
DISPLAY INVISIBLE (-3500 1600);
FORCEPROP 1 LAST HDL_POWER GND
J 1
(-3550 1525);
DISPLAY 0.872340 (-3550 1525);
PAINT GREEN (-3550 1525);
DISPLAY INVISIBLE (-3550 1525);
FORCEADD Q_CAP..1
R 1
(-4575 2950);
FORCEPROP 1 LAST LOCATION PC113
J 0
(-4625 3000);
DISPLAY 0.489362 (-4625 3000);
PAINT SKYBLUE (-4625 3000);
FORCEPROP 0 LAST $SEC 1
R 1
J 0
(-4575 3025);
DISPLAY 0.680851 (-4575 3025);
PAINT MONO (-4575 3025);
DISPLAY INVISIBLE (-4575 3025);
FORCEPROP 0 LAST CDS_SEC 1
R 1
J 0
(-4575 3025);
DISPLAY 1.021277 (-4575 3025);
DISPLAY INVISIBLE (-4575 3025);
FORCEPROP 1 LASTPIN (-4675 2950) $PN 1
R 1
J 0
(-4655 2960);
DISPLAY 0.489362 (-4655 2960);
PAINT MONO (-4655 2960);
FORCEPROP 1 LASTPIN (-4475 2950) $PN 2
R 1
J 0
(-4455 2960);
DISPLAY 0.489362 (-4455 2960);
PAINT MONO (-4455 2960);
FORCEPROP 1 LAST MATERIAL X7R
J 0
(-4500 2875);
DISPLAY 0.489362 (-4500 2875);
PAINT SKYBLUE (-4500 2875);
FORCEPROP 1 LAST TOLERANCE 10%
J 0
(-4700 2825);
DISPLAY 0.489362 (-4700 2825);
PAINT SKYBLUE (-4700 2825);
FORCEPROP 1 LAST VALUE 0.1UF
J 0
(-4750 2975);
DISPLAY 0.489362 (-4750 2975);
PAINT SKYBLUE (-4750 2975);
FORCEPROP 1 LAST PART_NUMBER CH4104K1B00
J 0
(-4800 2875);
DISPLAY 0.489362 (-4800 2875);
PAINT SKYBLUE (-4800 2875);
FORCEPROP 1 LAST VOLTAGE 25V
J 0
(-4500 3000);
DISPLAY 0.489362 (-4500 3000);
PAINT SKYBLUE (-4500 3000);
FORCEPROP 1 LAST PACK_TYPE 0402
J 0
(-4525 2825);
DISPLAY 0.489362 (-4525 2825);
PAINT SKYBLUE (-4525 2825);
FORCEPROP 2 LAST CDS_LIB pure_quanta
J 0
(-4575 2950);
DISPLAY INVISIBLE (-4575 2950);
FORCEPROP 1 LAST PATH I44
R 1
J 0
(-4725 3000);
DISPLAY 0.978723 (-4725 3000);
PAINT WHITE (-4725 3000);
DISPLAY INVISIBLE (-4725 3000);
FORCEADD Q_CAP..1
(-8350 4200);
FORCEPROP 1 LAST LOCATION PC111
J 0
(-8300 4300);
DISPLAY 0.489362 (-8300 4300);
PAINT SKYBLUE (-8300 4300);
FORCEPROP 0 LAST $SEC 1
J 0
(-8300 4325);
DISPLAY 0.680851 (-8300 4325);
PAINT MONO (-8300 4325);
DISPLAY INVISIBLE (-8300 4325);
FORCEPROP 0 LAST CDS_SEC 1
J 0
(-8300 4325);
DISPLAY 1.021277 (-8300 4325);
DISPLAY INVISIBLE (-8300 4325);
FORCEPROP 1 LASTPIN (-8350 4300) $PN 1
J 0
(-8340 4280);
DISPLAY 0.489362 (-8340 4280);
PAINT MONO (-8340 4280);
FORCEPROP 1 LASTPIN (-8350 4100) $PN 2
J 0
(-8340 4080);
DISPLAY 0.489362 (-8340 4080);
PAINT MONO (-8340 4080);
FORCEPROP 1 LAST MATERIAL X6S
J 0
(-8300 4100);
DISPLAY 0.489362 (-8300 4100);
PAINT SKYBLUE (-8300 4100);
FORCEPROP 1 LAST TOLERANCE 10%
J 0
(-8300 4150);
DISPLAY 0.489362 (-8300 4150);
PAINT SKYBLUE (-8300 4150);
FORCEPROP 1 LAST VALUE 10UF
J 0
(-8300 4250);
DISPLAY 0.489362 (-8300 4250);
PAINT SKYBLUE (-8300 4250);
FORCEPROP 1 LAST PART_NUMBER CH6104KEA00
J 0
(-8300 4050);
DISPLAY 0.489362 (-8300 4050);
PAINT SKYBLUE (-8300 4050);
FORCEPROP 1 LAST VOLTAGE 25V
J 0
(-8300 4200);
DISPLAY 0.489362 (-8300 4200);
PAINT SKYBLUE (-8300 4200);
FORCEPROP 1 LAST PACK_TYPE C0805
J 0
(-8300 4000);
DISPLAY 0.489362 (-8300 4000);
PAINT SKYBLUE (-8300 4000);
FORCEPROP 2 LAST CDS_LIB pure_quanta
J 0
(-8350 4200);
DISPLAY INVISIBLE (-8350 4200);
FORCEPROP 1 LAST PATH I45
J 0
(-8300 4350);
DISPLAY 0.978723 (-8300 4350);
PAINT WHITE (-8300 4350);
DISPLAY INVISIBLE (-8300 4350);
FORCEADD UNIVERSAL_GND..1
(-7950 3825);
FORCEPROP 3 LASTPIN (-7950 3875) SIG_NAME GND\g
J 0
(-7940 3885);
DISPLAY 0.659574 (-7940 3885);
PAINT MONO (-7940 3885);
DISPLAY INVISIBLE (-7940 3885);
FORCEPROP 2 LAST CDS_LIB pure_quanta_power
J 0
(-7950 3825);
DISPLAY INVISIBLE (-7950 3825);
FORCEPROP 1 LAST PATH I46
J 0
(-7875 3825);
DISPLAY 0.872340 (-7875 3825);
PAINT AQUA (-7875 3825);
DISPLAY INVISIBLE (-7875 3825);
FORCEPROP 1 LAST HDL_POWER GND
J 1
(-7925 3750);
DISPLAY 0.872340 (-7925 3750);
PAINT GREEN (-7925 3750);
DISPLAY INVISIBLE (-7925 3750);
FORCEADD Q_CAP..1
(-2925 3400);
FORCEPROP 1 LAST LOCATION PC114
J 0
(-2875 3500);
DISPLAY 0.489362 (-2875 3500);
PAINT SKYBLUE (-2875 3500);
FORCEPROP 0 LAST $SEC 1
J 0
(-2875 3525);
DISPLAY 0.680851 (-2875 3525);
PAINT MONO (-2875 3525);
DISPLAY INVISIBLE (-2875 3525);
FORCEPROP 0 LAST CDS_SEC 1
J 0
(-2875 3525);
DISPLAY 1.021277 (-2875 3525);
DISPLAY INVISIBLE (-2875 3525);
FORCEPROP 1 LASTPIN (-2925 3500) $PN 1
J 0
(-2915 3480);
DISPLAY 0.489362 (-2915 3480);
PAINT MONO (-2915 3480);
FORCEPROP 1 LASTPIN (-2925 3300) $PN 2
J 0
(-2915 3280);
DISPLAY 0.489362 (-2915 3280);
PAINT MONO (-2915 3280);
FORCEPROP 1 LAST MATERIAL X6S
J 0
(-2875 3300);
DISPLAY 0.489362 (-2875 3300);
PAINT SKYBLUE (-2875 3300);
FORCEPROP 1 LAST TOLERANCE 20%
J 0
(-2875 3350);
DISPLAY 0.489362 (-2875 3350);
PAINT SKYBLUE (-2875 3350);
FORCEPROP 1 LAST VALUE 22UF
J 0
(-2875 3450);
DISPLAY 0.489362 (-2875 3450);
PAINT SKYBLUE (-2875 3450);
FORCEPROP 1 LAST PART_NUMBER TMP_QCH622KMEA01
J 0
(-2875 3250);
DISPLAY 0.489362 (-2875 3250);
PAINT SKYBLUE (-2875 3250);
FORCEPROP 1 LAST VOLTAGE 4V
J 0
(-2875 3400);
DISPLAY 0.489362 (-2875 3400);
PAINT SKYBLUE (-2875 3400);
FORCEPROP 1 LAST PACK_TYPE 0805
J 0
(-2875 3200);
DISPLAY 0.489362 (-2875 3200);
PAINT SKYBLUE (-2875 3200);
FORCEPROP 2 LAST CDS_LIB pure_quanta
J 0
(-2925 3400);
DISPLAY INVISIBLE (-2925 3400);
FORCEPROP 1 LAST PATH I48
J 0
(-2875 3550);
DISPLAY 0.978723 (-2875 3550);
PAINT WHITE (-2875 3550);
DISPLAY INVISIBLE (-2875 3550);
FORCEADD Q_CAP..1
(-7975 4200);
FORCEPROP 1 LAST LOCATION PC227
J 0
(-7925 4300);
DISPLAY 0.489362 (-7925 4300);
PAINT SKYBLUE (-7925 4300);
FORCEPROP 0 LAST $SEC 1
J 0
(-7925 4325);
DISPLAY 0.680851 (-7925 4325);
PAINT MONO (-7925 4325);
DISPLAY INVISIBLE (-7925 4325);
FORCEPROP 0 LAST CDS_SEC 1
J 0
(-7925 4350);
DISPLAY 1.021277 (-7925 4350);
DISPLAY INVISIBLE (-7925 4350);
FORCEPROP 1 LASTPIN (-7975 4300) $PN 1
J 0
(-7965 4280);
DISPLAY 0.489362 (-7965 4280);
PAINT MONO (-7965 4280);
FORCEPROP 1 LASTPIN (-7975 4100) $PN 2
J 0
(-7965 4080);
DISPLAY 0.489362 (-7965 4080);
PAINT MONO (-7965 4080);
FORCEPROP 1 LAST MATERIAL X6S
J 0
(-7925 4100);
DISPLAY 0.489362 (-7925 4100);
PAINT SKYBLUE (-7925 4100);
FORCEPROP 1 LAST TOLERANCE 10%
J 0
(-7925 4150);
DISPLAY 0.489362 (-7925 4150);
PAINT SKYBLUE (-7925 4150);
FORCEPROP 1 LAST VALUE 10UF
J 0
(-7925 4250);
DISPLAY 0.489362 (-7925 4250);
PAINT SKYBLUE (-7925 4250);
FORCEPROP 1 LAST PART_NUMBER CH6104KEA00
J 0
(-7925 4050);
DISPLAY 0.489362 (-7925 4050);
PAINT SKYBLUE (-7925 4050);
FORCEPROP 1 LAST VOLTAGE 25V
J 0
(-7925 4200);
DISPLAY 0.489362 (-7925 4200);
PAINT SKYBLUE (-7925 4200);
FORCEPROP 1 LAST PACK_TYPE C0805
J 0
(-7925 4000);
DISPLAY 0.489362 (-7925 4000);
PAINT SKYBLUE (-7925 4000);
FORCEPROP 2 LAST CDS_LIB pure_quanta
J 0
(-7975 4200);
DISPLAY INVISIBLE (-7975 4200);
FORCEPROP 1 LAST PATH I5
J 0
(-7925 4350);
DISPLAY 0.978723 (-7925 4350);
PAINT WHITE (-7925 4350);
DISPLAY INVISIBLE (-7925 4350);
FORCEADD UNIVERSAL_GND..1
(-8050 3000);
FORCEPROP 3 LASTPIN (-8050 3050) SIG_NAME GND\g
J 0
(-8040 3060);
DISPLAY 0.659574 (-8040 3060);
PAINT MONO (-8040 3060);
DISPLAY INVISIBLE (-8040 3060);
FORCEPROP 2 LAST CDS_LIB pure_quanta_power
J 0
(-8050 3000);
DISPLAY INVISIBLE (-8050 3000);
FORCEPROP 1 LAST PATH I50
J 0
(-7975 3000);
DISPLAY 0.872340 (-7975 3000);
PAINT AQUA (-7975 3000);
DISPLAY INVISIBLE (-7975 3000);
FORCEPROP 1 LAST HDL_POWER GND
J 1
(-8025 2925);
DISPLAY 0.872340 (-8025 2925);
PAINT GREEN (-8025 2925);
DISPLAY INVISIBLE (-8025 2925);
FORCEADD Q_RES..1
(-7075 3450);
FORCEPROP 1 LAST LOCATION PR417
J 0
(-7100 3500);
DISPLAY 0.489362 (-7100 3500);
PAINT SKYBLUE (-7100 3500);
FORCEPROP 0 LAST $SEC 1
J 0
(-7125 3525);
DISPLAY 0.680851 (-7125 3525);
PAINT MONO (-7125 3525);
DISPLAY INVISIBLE (-7125 3525);
FORCEPROP 0 LAST CDS_SEC 1
J 0
(-7125 3525);
DISPLAY 1.021277 (-7125 3525);
DISPLAY INVISIBLE (-7125 3525);
FORCEPROP 1 LASTPIN (-7175 3450) $PN 1
J 0
(-7163 3462);
DISPLAY 0.489362 (-7163 3462);
PAINT MONO (-7163 3462);
FORCEPROP 1 LASTPIN (-6975 3450) $PN 2
J 0
(-7013 3462);
DISPLAY 0.489362 (-7013 3462);
PAINT MONO (-7013 3462);
FORCEPROP 1 LAST PACK_TYPE 0402LF
J 0
(-7000 3375);
DISPLAY 0.489362 (-7000 3375);
PAINT SKYBLUE (-7000 3375);
FORCEPROP 1 LAST WATTAGE 1/16W
J 0
(-7000 3350);
DISPLAY 0.489362 (-7000 3350);
PAINT SKYBLUE (-7000 3350);
FORCEPROP 1 LAST MATERIAL CHIP
J 0
(-7375 3350);
DISPLAY 0.489362 (-7375 3350);
PAINT SKYBLUE (-7375 3350);
FORCEPROP 1 LAST TOLERANCE 5%
J 0
(-6950 3475);
DISPLAY 0.489362 (-6950 3475);
PAINT SKYBLUE (-6950 3475);
FORCEPROP 1 LAST VALUE 0
J 2
(-7250 3475);
DISPLAY 0.489362 (-7250 3475);
PAINT SKYBLUE (-7250 3475);
FORCEPROP 1 LAST PART_NUMBER CS00002JB38
J 0
(-7375 3375);
DISPLAY 0.489362 (-7375 3375);
PAINT SKYBLUE (-7375 3375);
FORCEPROP 2 LAST CDS_LIB pure_quanta
J 0
(-7075 3450);
DISPLAY INVISIBLE (-7075 3450);
FORCEPROP 1 LAST PATH I51
J 0
(-7125 3600);
DISPLAY 0.978723 (-7125 3600);
PAINT WHITE (-7125 3600);
DISPLAY INVISIBLE (-7125 3600);
FORCEADD Q_CAPP..1
(-1425 3400);
FORCEPROP 1 LAST LOCATION PC115
J 0
(-1375 3500);
DISPLAY 0.489362 (-1375 3500);
PAINT SKYBLUE (-1375 3500);
FORCEPROP 0 LAST $SEC 1
J 0
(-1375 3525);
DISPLAY 0.680851 (-1375 3525);
PAINT MONO (-1375 3525);
DISPLAY INVISIBLE (-1375 3525);
FORCEPROP 0 LAST CDS_SEC 1
J 0
(-1375 3525);
DISPLAY 1.021277 (-1375 3525);
DISPLAY INVISIBLE (-1375 3525);
FORCEPROP 1 LASTPIN (-1425 3500) $PN 1
J 0
(-1415 3485);
DISPLAY 0.489362 (-1415 3485);
PAINT MONO (-1415 3485);
FORCEPROP 1 LASTPIN (-1425 3300) $PN 2
J 0
(-1415 3285);
DISPLAY 0.489362 (-1415 3285);
PAINT MONO (-1415 3285);
FORCEPROP 1 LAST MATERIAL OSCON
J 0
(-1375 3300);
DISPLAY 0.489362 (-1375 3300);
PAINT SKYBLUE (-1375 3300);
FORCEPROP 1 LAST TOLERANCE 20%
J 0
(-1375 3400);
DISPLAY 0.489362 (-1375 3400);
PAINT SKYBLUE (-1375 3400);
FORCEPROP 1 LAST VALUE 390UF
J 0
(-1375 3450);
DISPLAY 0.489362 (-1375 3450);
PAINT SKYBLUE (-1375 3450);
FORCEPROP 1 LAST PART_NUMBER CC7390JMZ12
J 0
(-1375 3200);
DISPLAY 0.489362 (-1375 3200);
PAINT SKYBLUE (-1375 3200);
FORCEPROP 1 LAST VOLTAGE 2.5V
J 0
(-1375 3350);
DISPLAY 0.489362 (-1375 3350);
PAINT SKYBLUE (-1375 3350);
FORCEPROP 1 LAST PACK_TYPE SMLF
J 0
(-1375 3250);
DISPLAY 0.489362 (-1375 3250);
PAINT SKYBLUE (-1375 3250);
FORCEPROP 2 LAST CDS_LIB pure_quanta
J 0
(-1425 3400);
DISPLAY INVISIBLE (-1425 3400);
FORCEPROP 1 LAST PATH I54
J 0
(-1375 3550);
DISPLAY 0.978723 (-1375 3550);
DISPLAY INVISIBLE (-1375 3550);
FORCEADD Q_RES..2
(-500 3375);
FORCEPROP 1 LAST LOCATION PR439
J 0
(-455 3500);
DISPLAY 0.489362 (-455 3500);
PAINT SKYBLUE (-455 3500);
FORCEPROP 0 LAST $SEC 1
J 0
(-450 3525);
DISPLAY 0.680851 (-450 3525);
PAINT MONO (-450 3525);
DISPLAY INVISIBLE (-450 3525);
FORCEPROP 0 LAST CDS_SEC 1
J 0
(-450 3525);
DISPLAY 1.021277 (-450 3525);
DISPLAY INVISIBLE (-450 3525);
FORCEPROP 1 LASTPIN (-500 3475) $PN 1
J 0
(-495 3437);
DISPLAY 0.489362 (-495 3437);
PAINT MONO (-495 3437);
FORCEPROP 1 LASTPIN (-500 3275) $PN 2
J 0
(-495 3285);
DISPLAY 0.489362 (-495 3285);
PAINT MONO (-495 3285);
FORCEPROP 1 LAST WATTAGE 1/16W
J 0
(-460 3350);
DISPLAY 0.489362 (-460 3350);
PAINT SKYBLUE (-460 3350);
FORCEPROP 1 LAST MATERIAL CHIP
J 0
(-460 3300);
DISPLAY 0.489362 (-460 3300);
PAINT SKYBLUE (-460 3300);
FORCEPROP 1 LAST TOLERANCE 1%
J 0
(-455 3400);
DISPLAY 0.489362 (-455 3400);
PAINT SKYBLUE (-455 3400);
FORCEPROP 1 LAST VALUE 1K
J 0
(-455 3450);
DISPLAY 0.489362 (-455 3450);
PAINT SKYBLUE (-455 3450);
FORCEPROP 1 LAST PART_NUMBER TMP_QCS21002FB24
J 0
(-460 3250);
DISPLAY 0.489362 (-460 3250);
PAINT SKYBLUE (-460 3250);
FORCEPROP 1 LAST PACK_TYPE 0402LF
J 0
(-460 3200);
DISPLAY 0.489362 (-460 3200);
PAINT SKYBLUE (-460 3200);
FORCEPROP 2 LAST CDS_LIB pure_quanta
J 0
(-500 3375);
DISPLAY INVISIBLE (-500 3375);
FORCEPROP 1 LAST PATH I56
J 0
(-450 3550);
DISPLAY 0.978723 (-450 3550);
PAINT WHITE (-450 3550);
DISPLAY INVISIBLE (-450 3550);
FORCEADD Q_CAP..1
(-1100 3400);
FORCEPROP 1 LAST LOCATION PC215
J 0
(-1050 3500);
DISPLAY 0.489362 (-1050 3500);
PAINT SKYBLUE (-1050 3500);
FORCEPROP 2 LAST SEC 1
J 0
(-1048 3607);
DISPLAY 0.680851 (-1048 3607);
PAINT MONO (-1048 3607);
DISPLAY INVISIBLE (-1048 3607);
FORCEPROP 1 LASTPIN (-1100 3500) $PN 1
J 0
(-1090 3480);
DISPLAY 0.489362 (-1090 3480);
FORCEPROP 1 LASTPIN (-1100 3300) $PN 2
J 0
(-1090 3280);
DISPLAY 0.489362 (-1090 3280);
FORCEPROP 1 LAST MATERIAL X7R
J 0
(-1050 3300);
DISPLAY 0.489362 (-1050 3300);
PAINT SKYBLUE (-1050 3300);
FORCEPROP 1 LAST TOLERANCE 10%
J 0
(-1050 3350);
DISPLAY 0.489362 (-1050 3350);
PAINT SKYBLUE (-1050 3350);
FORCEPROP 1 LAST VALUE 0.1UF
J 0
(-1050 3450);
DISPLAY 0.489362 (-1050 3450);
PAINT SKYBLUE (-1050 3450);
FORCEPROP 1 LAST PART_NUMBER CH4104K1B00
J 0
(-1050 3250);
DISPLAY 0.489362 (-1050 3250);
PAINT SKYBLUE (-1050 3250);
FORCEPROP 1 LAST VOLTAGE 25V
J 0
(-1050 3400);
DISPLAY 0.489362 (-1050 3400);
PAINT SKYBLUE (-1050 3400);
FORCEPROP 1 LAST PACK_TYPE 0402
J 0
(-1050 3200);
DISPLAY 0.489362 (-1050 3200);
PAINT SKYBLUE (-1050 3200);
FORCEPROP 2 LAST CDS_LIB pure_quanta
J 0
(-1100 3400);
PAINT MONO (-1100 3400);
DISPLAY INVISIBLE (-1100 3400);
FORCEPROP 2 LAST SEC_TYPE 0402
J 0
(-1050 3596);
DISPLAY 1.021277 (-1050 3596);
DISPLAY INVISIBLE (-1050 3596);
FORCEPROP 1 LAST PATH I57
J 0
(-1050 3550);
DISPLAY 0.978723 (-1050 3550);
PAINT WHITE (-1050 3550);
DISPLAY INVISIBLE (-1050 3550);
FORCEADD UNIVERSAL_GND..1
(-1100 3025);
FORCEPROP 3 LASTPIN (-1100 3075) SIG_NAME GND\g
J 0
(-1090 3085);
DISPLAY 0.659574 (-1090 3085);
PAINT MONO (-1090 3085);
DISPLAY INVISIBLE (-1090 3085);
FORCEPROP 2 LAST CDS_LIB pure_quanta_power
J 0
(-1100 3025);
DISPLAY INVISIBLE (-1100 3025);
FORCEPROP 1 LAST PATH I58
J 0
(-1025 3025);
DISPLAY 0.872340 (-1025 3025);
PAINT AQUA (-1025 3025);
DISPLAY INVISIBLE (-1025 3025);
FORCEPROP 1 LAST HDL_POWER GND
J 1
(-1075 2950);
DISPLAY 0.872340 (-1075 2950);
PAINT GREEN (-1075 2950);
DISPLAY INVISIBLE (-1075 2950);
FORCEADD Q_RES..1
(-1700 2900);
FORCEPROP 1 LAST LOCATION PR438
J 0
(-1725 2950);
DISPLAY 0.489362 (-1725 2950);
PAINT SKYBLUE (-1725 2950);
FORCEPROP 0 LAST $SEC 1
J 0
(-1750 3000);
DISPLAY 0.680851 (-1750 3000);
PAINT MONO (-1750 3000);
DISPLAY INVISIBLE (-1750 3000);
FORCEPROP 0 LAST CDS_SEC 1
J 0
(-1750 3000);
DISPLAY 1.021277 (-1750 3000);
DISPLAY INVISIBLE (-1750 3000);
FORCEPROP 1 LASTPIN (-1800 2900) $PN 1
J 0
(-1788 2912);
DISPLAY 0.489362 (-1788 2912);
PAINT MONO (-1788 2912);
FORCEPROP 1 LASTPIN (-1600 2900) $PN 2
J 0
(-1638 2912);
DISPLAY 0.489362 (-1638 2912);
PAINT MONO (-1638 2912);
FORCEPROP 1 LAST WATTAGE 1/16W
J 2
(-1450 2925);
DISPLAY 0.489362 (-1450 2925);
PAINT SKYBLUE (-1450 2925);
FORCEPROP 1 LAST MATERIAL CHIP
J 0
(-1575 2850);
DISPLAY 0.489362 (-1575 2850);
PAINT SKYBLUE (-1575 2850);
FORCEPROP 1 LAST TOLERANCE 1%
J 0
(-1875 2800);
DISPLAY 0.489362 (-1875 2800);
PAINT SKYBLUE (-1875 2800);
FORCEPROP 1 LAST VALUE 49.9
J 2
(-1825 2950);
DISPLAY 0.489362 (-1825 2950);
PAINT SKYBLUE (-1825 2950);
FORCEPROP 1 LAST PART_NUMBER CS04992FB07
J 0
(-2000 2850);
DISPLAY 0.489362 (-2000 2850);
PAINT SKYBLUE (-2000 2850);
FORCEPROP 1 LAST PACK_TYPE 0402LF
J 0
(-1600 2825);
DISPLAY 0.489362 (-1600 2825);
PAINT SKYBLUE (-1600 2825);
FORCEPROP 2 LAST CDS_LIB pure_quanta
R 3
J 0
(-1700 2900);
DISPLAY INVISIBLE (-1700 2900);
FORCEPROP 1 LAST PATH I59
J 0
(-1750 3050);
DISPLAY 0.978723 (-1750 3050);
PAINT WHITE (-1750 3050);
DISPLAY INVISIBLE (-1750 3050);
FORCEADD P1V0_AUX..1
(-9146 4645);
FORCEPROP 3 LASTPIN (-9146 4595) SIG_NAME P12V_STBY\g
J 0
(-9136 4605);
DISPLAY 0.659574 (-9136 4605);
PAINT MONO (-9136 4605);
DISPLAY INVISIBLE (-9136 4605);
FORCEPROP 1 LAST HDL_POWER P12V_STBY
J 1
(-9135 4692);
DISPLAY 0.489362 (-9135 4692);
PAINT GREEN (-9135 4692);
FORCEPROP 2 LAST CDS_LIB mstr_symbols
J 0
(-9146 4645);
DISPLAY INVISIBLE (-9146 4645);
FORCEPROP 1 LAST BODY_TYPE PLUMBING
J 0
(-9191 4602);
DISPLAY 0.340426 (-9191 4602);
PAINT GREEN (-9191 4602);
DISPLAY INVISIBLE (-9191 4602);
FORCEPROP 1 LAST PATH I6
J 0
(-9096 4670);
DISPLAY 0.872340 (-9096 4670);
PAINT AQUA (-9096 4670);
DISPLAY INVISIBLE (-9096 4670);
FORCEPROP 1 LAST VOLTAGE 1.0V
J 0
(-9191 4602);
DISPLAY 0.340426 (-9191 4602);
PAINT SKYBLUE (-9191 4602);
DISPLAY INVISIBLE (-9191 4602);
FORCEPROP 2 LAST ROOM VR_DDR1_POWER_STAGE
J 0
(-9146 4745);
DISPLAY 0.978723 (-9146 4745);
PAINT RED (-9146 4745);
DISPLAY INVISIBLE (-9146 4745);
FORCEADD Q_CAP..1
(-2475 3400);
FORCEPROP 1 LAST LOCATION PC285
J 0
(-2425 3500);
DISPLAY 0.489362 (-2425 3500);
PAINT SKYBLUE (-2425 3500);
FORCEPROP 0 LAST $SEC 1
J 0
(-2425 3550);
DISPLAY 0.680851 (-2425 3550);
PAINT MONO (-2425 3550);
DISPLAY INVISIBLE (-2425 3550);
FORCEPROP 0 LAST CDS_SEC 1
J 0
(-2425 3550);
DISPLAY 1.021277 (-2425 3550);
DISPLAY INVISIBLE (-2425 3550);
FORCEPROP 1 LASTPIN (-2475 3500) $PN 1
J 0
(-2465 3480);
DISPLAY 0.489362 (-2465 3480);
PAINT MONO (-2465 3480);
FORCEPROP 1 LASTPIN (-2475 3300) $PN 2
J 0
(-2465 3280);
DISPLAY 0.489362 (-2465 3280);
PAINT MONO (-2465 3280);
FORCEPROP 1 LAST MATERIAL X6S
J 0
(-2425 3300);
DISPLAY 0.489362 (-2425 3300);
PAINT SKYBLUE (-2425 3300);
FORCEPROP 1 LAST TOLERANCE 20%
J 0
(-2425 3350);
DISPLAY 0.489362 (-2425 3350);
PAINT SKYBLUE (-2425 3350);
FORCEPROP 1 LAST VALUE 22UF
J 0
(-2425 3450);
DISPLAY 0.489362 (-2425 3450);
PAINT SKYBLUE (-2425 3450);
FORCEPROP 1 LAST VOLTAGE 4V
J 0
(-2425 3400);
DISPLAY 0.489362 (-2425 3400);
PAINT SKYBLUE (-2425 3400);
FORCEPROP 1 LAST PACK_TYPE 0805
J 0
(-2425 3250);
DISPLAY 0.489362 (-2425 3250);
PAINT SKYBLUE (-2425 3250);
FORCEPROP 2 LAST CDS_LIB pure_quanta
J 0
(-2475 3400);
DISPLAY INVISIBLE (-2475 3400);
FORCEPROP 1 LAST PATH I60
J 0
(-2425 3550);
DISPLAY 0.978723 (-2425 3550);
PAINT WHITE (-2425 3550);
DISPLAY INVISIBLE (-2425 3550);
FORCEPROP 1 LAST PART_NUMBER TMP_QCH622KMEA01
J 0
(-2425 3250);
DISPLAY 0.489362 (-2425 3250);
PAINT SKYBLUE (-2425 3250);
DISPLAY INVISIBLE (-2425 3250);
FORCEADD OFFPAGE..2
(-2600 4150);
FORCEPROP 2 LAST $XR0 80 
J 0
(-2411 4150);
DISPLAY 0.638298 (-2411 4150);
PAINT MONO (-2411 4150);
FORCEPROP 2 LAST CDS_LIB standard
J 0
(-2600 4150);
DISPLAY INVISIBLE (-2600 4150);
FORCEPROP 1 LAST OFFPAGE TRUE
J 0
(-2275 4025);
DISPLAY 1.170213 (-2275 4025);
PAINT GREEN (-2275 4025);
DISPLAY INVISIBLE (-2275 4025);
FORCEPROP 1 LAST COMMENT_BODY TRUE
J 0
(-2645 4055);
DISPLAY 1.170213 (-2645 4055);
PAINT GREEN (-2645 4055);
DISPLAY INVISIBLE (-2645 4055);
FORCEPROP 2 LAST PATH I61
J 0
(-2225 4200);
DISPLAY 0.680851 (-2225 4200);
DISPLAY INVISIBLE (-2225 4200);
FORCEPROP 2 LAST ROOM VR_CORE0_CTRL
J 2
(-2325 4200);
PAINT RED (-2325 4200);
DISPLAY INVISIBLE (-2325 4200);
FORCEADD Q_RES..1
(-3650 4150);
FORCEPROP 1 LAST LOCATION R177
J 0
(-3525 4150);
DISPLAY 0.489362 (-3525 4150);
PAINT SKYBLUE (-3525 4150);
FORCEPROP 0 LAST $SEC 1
J 2
(-3525 4200);
DISPLAY 0.680851 (-3525 4200);
PAINT MONO (-3525 4200);
DISPLAY INVISIBLE (-3525 4200);
FORCEPROP 0 LAST CDS_SEC 1
J 2
(-3525 4200);
DISPLAY 1.021277 (-3525 4200);
DISPLAY INVISIBLE (-3525 4200);
FORCEPROP 1 LASTPIN (-3750 4150) $PN 1
J 0
(-3738 4162);
DISPLAY 0.489362 (-3738 4162);
PAINT MONO (-3738 4162);
FORCEPROP 1 LASTPIN (-3550 4150) $PN 2
J 0
(-3588 4162);
DISPLAY 0.489362 (-3588 4162);
PAINT MONO (-3588 4162);
FORCEPROP 1 LAST VALUE 33
J 2
(-3775 4150);
DISPLAY 0.489362 (-3775 4150);
PAINT SKYBLUE (-3775 4150);
FORCEPROP 2 LAST CDS_LIB pure_quanta
J 2
(-3650 4150);
DISPLAY INVISIBLE (-3650 4150);
FORCEPROP 2 LAST BOM_COST MEM
J 2
(-3625 4300);
DISPLAY 0.744681 (-3625 4300);
PAINT WHITE (-3625 4300);
DISPLAY INVISIBLE (-3625 4300);
FORCEPROP 1 LAST PATH I62
J 0
(-3700 4300);
DISPLAY 0.978723 (-3700 4300);
PAINT WHITE (-3700 4300);
DISPLAY INVISIBLE (-3700 4300);
FORCEPROP 1 LAST WATTAGE 1/16W
J 2
(-3725 4075);
DISPLAY 0.489362 (-3725 4075);
PAINT SKYBLUE (-3725 4075);
DISPLAY INVISIBLE (-3725 4075);
FORCEPROP 1 LAST MATERIAL CHIP
J 2
(-3475 4125);
DISPLAY 0.489362 (-3475 4125);
PAINT SKYBLUE (-3475 4125);
DISPLAY INVISIBLE (-3475 4125);
FORCEPROP 1 LAST TOLERANCE 5%
J 0
(-3775 4125);
DISPLAY 0.489362 (-3775 4125);
PAINT SKYBLUE (-3775 4125);
DISPLAY INVISIBLE (-3775 4125);
FORCEPROP 1 LAST PART_NUMBER CS03302JB29
J 2
(-3550 4200);
DISPLAY 0.489362 (-3550 4200);
PAINT SKYBLUE (-3550 4200);
DISPLAY INVISIBLE (-3550 4200);
FORCEPROP 1 LAST PACK_TYPE 0402LF
J 2
(-3475 4075);
DISPLAY 0.489362 (-3475 4075);
PAINT SKYBLUE (-3475 4075);
DISPLAY INVISIBLE (-3475 4075);
FORCEPROP 2 LAST ROOM RST_CPU0_PLD_TO_DIMM
J 2
(-3625 4250);
DISPLAY 0.744681 (-3625 4250);
PAINT RED (-3625 4250);
DISPLAY INVISIBLE (-3625 4250);
FORCEADD UNIVERSAL_GND..1
(-8575 3250);
FORCEPROP 3 LASTPIN (-8575 3300) SIG_NAME GND\g
J 0
(-8565 3310);
DISPLAY 0.659574 (-8565 3310);
PAINT MONO (-8565 3310);
DISPLAY INVISIBLE (-8565 3310);
FORCEPROP 2 LAST CDS_LIB pure_quanta_power
J 0
(-8575 3250);
DISPLAY INVISIBLE (-8575 3250);
FORCEPROP 1 LAST PATH I63
J 0
(-8500 3250);
DISPLAY 0.872340 (-8500 3250);
PAINT AQUA (-8500 3250);
DISPLAY INVISIBLE (-8500 3250);
FORCEPROP 1 LAST HDL_POWER GND
J 1
(-8550 3175);
DISPLAY 0.872340 (-8550 3175);
PAINT GREEN (-8550 3175);
DISPLAY INVISIBLE (-8550 3175);
FORCEADD Q_CAP..1
R 2
(-8575 3450);
FORCEPROP 1 LAST LOCATION C674
J 2
(-8625 3550);
DISPLAY 0.489362 (-8625 3550);
PAINT SKYBLUE (-8625 3550);
FORCEPROP 0 LAST $SEC 1
J 0
(-8625 3600);
DISPLAY 0.680851 (-8625 3600);
PAINT MONO (-8625 3600);
DISPLAY INVISIBLE (-8625 3600);
FORCEPROP 0 LAST CDS_SEC 1
J 0
(-8625 3600);
DISPLAY 0.680851 (-8625 3600);
DISPLAY INVISIBLE (-8625 3600);
FORCEPROP 1 LASTPIN (-8575 3550) $PN 1
J 2
(-8585 3530);
DISPLAY 0.489362 (-8585 3530);
PAINT MONO (-8585 3530);
FORCEPROP 1 LASTPIN (-8575 3350) $PN 2
J 2
(-8585 3330);
DISPLAY 0.489362 (-8585 3330);
PAINT MONO (-8585 3330);
FORCEPROP 1 LAST MATERIAL EMPTY
J 2
(-8625 3350);
DISPLAY 0.489362 (-8625 3350);
PAINT RED (-8625 3350);
FORCEPROP 1 LAST TOLERANCE 10%
J 2
(-8625 3400);
DISPLAY 0.489362 (-8625 3400);
PAINT SKYBLUE (-8625 3400);
FORCEPROP 1 LAST VALUE 0.1UF
J 2
(-8625 3500);
DISPLAY 0.489362 (-8625 3500);
PAINT SKYBLUE (-8625 3500);
FORCEPROP 1 LAST PART_NUMBER CH4104K1B00
J 2
(-8650 3300);
DISPLAY 0.489362 (-8650 3300);
PAINT SKYBLUE (-8650 3300);
FORCEPROP 1 LAST VOLTAGE 25V
J 2
(-8625 3450);
DISPLAY 0.489362 (-8625 3450);
PAINT SKYBLUE (-8625 3450);
FORCEPROP 1 LAST PACK_TYPE 0402
J 2
(-8625 3250);
DISPLAY 0.489362 (-8625 3250);
PAINT SKYBLUE (-8625 3250);
FORCEPROP 2 LAST CDS_LIB pure_quanta
J 0
(-8575 3450);
DISPLAY INVISIBLE (-8575 3450);
FORCEPROP 1 LAST PATH I64
J 2
(-8625 3600);
DISPLAY 0.978723 (-8625 3600);
PAINT WHITE (-8625 3600);
DISPLAY INVISIBLE (-8625 3600);
FORCEPROP 2 LAST ROOM VR_DDR0_CTRL
R 3
J 1
(-8631 3411);
DISPLAY 0.744681 (-8631 3411);
PAINT RED (-8631 3411);
DISPLAY INVISIBLE (-8631 3411);
FORCEADD UNIVERSAL_GND..1
(-7575 2400);
FORCEPROP 3 LASTPIN (-7575 2450) SIG_NAME GND\g
J 0
(-7565 2460);
DISPLAY 0.659574 (-7565 2460);
PAINT MONO (-7565 2460);
DISPLAY INVISIBLE (-7565 2460);
FORCEPROP 2 LAST CDS_LIB pure_quanta_power
J 0
(-7575 2400);
DISPLAY INVISIBLE (-7575 2400);
FORCEPROP 1 LAST PATH I7
J 0
(-7500 2400);
DISPLAY 0.872340 (-7500 2400);
PAINT AQUA (-7500 2400);
DISPLAY INVISIBLE (-7500 2400);
FORCEPROP 1 LAST HDL_POWER GND
J 1
(-7550 2325);
DISPLAY 0.872340 (-7550 2325);
PAINT GREEN (-7550 2325);
DISPLAY INVISIBLE (-7550 2325);
FORCEADD UNIVERSAL_GND..1
(-6700 2375);
FORCEPROP 3 LASTPIN (-6700 2425) SIG_NAME GND\g
J 0
(-6690 2435);
DISPLAY 0.659574 (-6690 2435);
PAINT MONO (-6690 2435);
DISPLAY INVISIBLE (-6690 2435);
FORCEPROP 2 LAST CDS_LIB pure_quanta_power
J 0
(-6700 2375);
DISPLAY INVISIBLE (-6700 2375);
FORCEPROP 1 LAST PATH I8
J 0
(-6625 2375);
DISPLAY 0.872340 (-6625 2375);
PAINT AQUA (-6625 2375);
DISPLAY INVISIBLE (-6625 2375);
FORCEPROP 1 LAST HDL_POWER GND
J 1
(-6675 2300);
DISPLAY 0.872340 (-6675 2300);
PAINT GREEN (-6675 2300);
DISPLAY INVISIBLE (-6675 2300);
FORCEADD Q_CAP..1
R 2
(-7575 2625);
FORCEPROP 1 LAST LOCATION PC212
J 0
(-7525 2765);
DISPLAY 0.489362 (-7525 2765);
PAINT SKYBLUE (-7525 2765);
FORCEPROP 2 LAST SEC 1
J 0
(-7625 2821);
DISPLAY 0.680851 (-7625 2821);
PAINT MONO (-7625 2821);
DISPLAY INVISIBLE (-7625 2821);
FORCEPROP 1 LASTPIN (-7575 2725) $PN 1
J 2
(-7529 2696);
DISPLAY 0.489362 (-7529 2696);
FORCEPROP 1 LASTPIN (-7575 2525) $PN 2
J 2
(-7531 2520);
DISPLAY 0.489362 (-7531 2520);
FORCEPROP 1 LAST MATERIAL X6S
J 0
(-7525 2556);
DISPLAY 0.489362 (-7525 2556);
PAINT SKYBLUE (-7525 2556);
FORCEPROP 1 LAST TOLERANCE 10%
J 0
(-7525 2605);
DISPLAY 0.489362 (-7525 2605);
PAINT SKYBLUE (-7525 2605);
FORCEPROP 1 LAST VALUE 1UF
J 0
(-7525 2703);
DISPLAY 0.489362 (-7525 2703);
PAINT SKYBLUE (-7525 2703);
FORCEPROP 1 LAST PART_NUMBER CH5104KEB02
J 0
(-7525 2458);
DISPLAY 0.489362 (-7525 2458);
PAINT SKYBLUE (-7525 2458);
FORCEPROP 1 LAST VOLTAGE 25V
J 0
(-7525 2654);
DISPLAY 0.489362 (-7525 2654);
PAINT SKYBLUE (-7525 2654);
FORCEPROP 1 LAST PACK_TYPE C0402
J 0
(-7525 2507);
DISPLAY 0.489362 (-7525 2507);
PAINT SKYBLUE (-7525 2507);
FORCEPROP 2 LAST CDS_LIB pure_quanta
J 0
(-7575 2625);
DISPLAY INVISIBLE (-7575 2625);
FORCEPROP 2 LAST SIGNAL_MODEL DEFAULT_CAPACITOR_100000PF_2_1
R 3
J 1
(-7645 2573);
DISPLAY 0.744681 (-7645 2573);
PAINT MONO (-7645 2573);
DISPLAY INVISIBLE (-7645 2573);
FORCEPROP 2 LAST SEC_TYPE C0402
J 0
(-7625 2821);
DISPLAY 1.021277 (-7625 2821);
DISPLAY INVISIBLE (-7625 2821);
FORCEPROP 1 LAST PATH I9
J 2
(-7625 2775);
DISPLAY 0.978723 (-7625 2775);
PAINT WHITE (-7625 2775);
DISPLAY INVISIBLE (-7625 2775);
FORCEPROP 2 LAST ROOM VR_DDR0_CTRL
R 3
J 1
(-7631 2586);
DISPLAY 0.744681 (-7631 2586);
PAINT RED (-7631 2586);
DISPLAY INVISIBLE (-7631 2586);
FORCEADD DNS..1
(-1975 3400);
PAINT RED (-1975 3400);
FORCEPROP 2 LAST CDS_LIB mstr_misc
J 0
(-1975 3400);
DISPLAY INVISIBLE (-1975 3400);
FORCEPROP 1 LAST COMMENT_BODY TRUE
R 1
J 0
(-1900 3175);
DISPLAY 0.872340 (-1900 3175);
PAINT GREEN (-1900 3175);
DISPLAY INVISIBLE (-1900 3175);
FORCEADD DNS..1
(-1675 3400);
PAINT RED (-1675 3400);
FORCEPROP 2 LAST CDS_LIB mstr_misc
J 0
(-1675 3400);
DISPLAY INVISIBLE (-1675 3400);
FORCEPROP 1 LAST COMMENT_BODY TRUE
R 1
J 0
(-1600 3175);
DISPLAY 0.872340 (-1600 3175);
PAINT GREEN (-1600 3175);
DISPLAY INVISIBLE (-1600 3175);
FORCEADD DNS..1
(-8600 3350);
PAINT RED (-8600 3350);
FORCEPROP 2 LAST CDS_LIB mstr_misc
J 0
(-8600 3350);
DISPLAY INVISIBLE (-8600 3350);
FORCEPROP 1 LAST COMMENT_BODY TRUE
J 0
(-8600 3350);
DISPLAY INVISIBLE (-8600 3350);
FORCEADD QUANTA_TITLE_BLOCK_C..1
(0 0);
FORCEPROP 0 LAST CDS_CON_LAST_MODIFIED Fri Mar 11 14:53:31 2022
J 0
(-1885 15);
DISPLAY INVISIBLE (-1885 15);
FORCEPROP 1 LAST CUSTOM_TXT_CDS <CON_LAST_MODIFIED>
J 0
(-1885 15);
DISPLAY 0.978723 (-1885 15);
FORCEPROP 2 LAST CUSTOM_TXT_CDS <XR_PAGE_TITLE>
J 0
(-7890 5250);
DISPLAY 0.638298 (-7890 5250);
PAINT PINK (-7890 5250);
DISPLAY INVISIBLE (-7890 5250);
FORCEPROP 1 LAST CUSTOM_TXT_CDS <NAME_2>
J 0
(-3175 50);
FORCEPROP 1 LAST CUSTOM_TXT_CDS <NAME_1>
J 0
(-3175 175);
FORCEPROP 1 LAST CUSTOM_TXT_CDS <Q_NUMBER>
J 0
(-1403 103);
DISPLAY 1.212766 (-1403 103);
FORCEPROP 1 LAST CUSTOM_TXT_CDS <Q_PROJ>
J 0
(-2382 102);
DISPLAY 1.212766 (-2382 102);
FORCEPROP 1 LAST CUSTOM_TXT_CDS <Q_REV>
J 0
(-184 103);
DISPLAY 1.212766 (-184 103);
FORCEPROP 1 LAST CUSTOM_TXT_CDS <CON_PAGE_NUM> OF <CON_TOTAL_PAGES>
J 0
(-446 18);
DISPLAY 0.978723 (-446 18);
FORCEPROP 1 LAST Q_DEPT BU9
J 1
(-3763 49);
DISPLAY 1.957447 (-3763 49);
PAINT GREEN (-3763 49);
FORCEPROP 1 LAST Q_TITLE PVDD18_S5_P0
J 0
(-9300 50);
DISPLAY 2.446809 (-9300 50);
PAINT GREEN (-9300 50);
FORCEPROP 1 LAST CDS_LMAN_SYM_OUTLINE -9475,6775,100,-125
J 0
(0 0);
DISPLAY 0.468085 (0 0);
PAINT GREEN (0 0);
DISPLAY INVISIBLE (0 0);
FORCEPROP 2 LAST CDS_LIB pure_quanta
J 0
(0 0);
DISPLAY INVISIBLE (0 0);
FORCEPROP 2 LAST PAGE_BORDER TRUE
J 0
(-7890 5250);
DISPLAY 0.638298 (-7890 5250);
PAINT PINK (-7890 5250);
DISPLAY INVISIBLE (-7890 5250);
FORCEPROP 1 LAST COMMENT_BODY TRUE
J 0
(12 -13);
DISPLAY 0.978723 (12 -13);
PAINT GREEN (12 -13);
DISPLAY INVISIBLE (12 -13);
FORCEPROP 2 LAST CDS_XR_PAGE_TITLE CR-185 : @T6G_MB_LIB.T6G(SCH_1):PAGE185
J 0
(-7890 5250);
DISPLAY 0.638298 (-7890 5250);
PAINT PINK (-7890 5250);
DISPLAY INVISIBLE (-7890 5250);
WIRE 16 -1 (-7575 3200)(-7575 3150);
WIRE 16 -1 (-5000 2575)(-5000 2675);
WIRE 16 -1 (-4700 4675)(-4700 4550);
WIRE 16 -1 (-500 2900)(-500 3275);
WIRE 16 -1 (-3575 1750)(-3575 1650);
WIRE 16 -1 (-8050 3450)(-7175 3450);
WIRE 16 -1 (-8050 3450)(-8050 3050);
WIRE 16 -1 (-8575 3300)(-8575 3350);
WIRE 16 -1 (-7575 2450)(-7575 2525);
WIRE 16 -1 (-6700 2525)(-6700 2425);
WIRE 16 -1 (-5350 4150)(-4700 4150);
WIRE 16 -1 (-4700 4150)(-3750 4150);
FORCEPROP 2 LAST SIG_NAME PWRGD_PVDD18_S5_P0
J 0
(-4385 4175);
DISPLAY 0.489362 (-4385 4175);
FORCEPROP 2 LASTPROP $XRERR UNIQUE?
J 0
(-4625 4175);
DISPLAY 0.638298 (-4625 4175);
PAINT MONO (-4625 4175);
DISPLAY INVISIBLE (-4625 4175);
WIRE 16 -1 (-4700 4350)(-4700 4150);
WIRE 17 273 (-1675 6575)(-1675 5625);
WIRE 17 273 (-1675 6575)(-100 6575);
WIRE 17 273 (-1675 5625)(-100 5625);
WIRE 17 273 (-100 6575)(-100 5625);
WIRE 16 -1 (-2650 4150)(-3550 4150);
FORCEPROP 2 LAST SIG_NAME FM_PWRGD_PVDD18_S5_P0
J 0
(-3335 4175);
DISPLAY 0.489362 (-3335 4175);
WIRE 17 273 (-2025 2500)(-2025 1975);
WIRE 17 273 (-2025 2500)(-1150 2500);
WIRE 17 273 (-2025 1975)(-1150 1975);
WIRE 17 273 (-1150 2500)(-1150 1975);
WIRE 16 -1 (-2500 2400)(-1450 2400);
FORCEPROP 2 LAST SIG_NAME VSENSE_PVDD18_S5_P0_DP
J 0
(-1985 2410);
DISPLAY 0.489362 (-1985 2410);
WIRE 16 -1 (-2500 2100)(-1450 2100);
FORCEPROP 2 LAST SIG_NAME VSENSE_PVDD18_S5_P0_DN
J 0
(-1985 2110);
DISPLAY 0.489362 (-1985 2110);
WIRE 17 273 (-3125 2575)(-700 2575);
WIRE 17 273 (-3125 2575)(-3125 1650);
WIRE 17 273 (-700 2575)(-700 1650);
WIRE 17 273 (-3125 1650)(-700 1650);
WIRE 16 -1 (-2925 3300)(-2925 3150);
WIRE 16 -1 (-2475 3150)(-2925 3150);
WIRE 16 -1 (-2475 3150)(-2275 3150);
WIRE 16 -1 (-2475 3300)(-2475 3150);
WIRE 16 -1 (-2275 3150)(-2025 3150);
WIRE 16 -1 (-2275 3300)(-2275 3150);
WIRE 16 -1 (-2025 3150)(-1700 3150);
WIRE 16 -1 (-2025 3300)(-2025 3150);
WIRE 16 -1 (-1425 3150)(-1700 3150);
WIRE 16 -1 (-1700 3300)(-1700 3150);
WIRE 16 -1 (-1100 3150)(-1425 3150);
WIRE 16 -1 (-1425 3150)(-1425 3300);
WIRE 16 -1 (-1100 3075)(-1100 3150);
WIRE 16 -1 (-1100 3150)(-1100 3300);
WIRE 16 -1 (-3475 3650)(-2925 3650);
WIRE 16 -1 (-2925 3650)(-2475 3650);
WIRE 16 -1 (-2925 3500)(-2925 3650);
WIRE 16 -1 (-2475 3650)(-2275 3650);
WIRE 16 -1 (-2475 3500)(-2475 3650);
WIRE 16 -1 (-2275 3500)(-2275 3650);
WIRE 16 -1 (-2275 3650)(-2025 3650);
WIRE 16 -1 (-2025 3650)(-1700 3650);
WIRE 16 -1 (-2025 3650)(-2025 3500);
WIRE 16 -1 (-1425 3650)(-1700 3650);
WIRE 16 -1 (-1700 3650)(-1700 3500);
WIRE 16 -1 (-1425 3650)(-1100 3650);
WIRE 16 -1 (-1425 3650)(-1425 3500);
WIRE 16 -1 (-500 3650)(-1100 3650);
WIRE 16 -1 (-1100 3650)(-1100 3550);
WIRE 16 -1 (-1100 3550)(-700 3550);
WIRE 16 -1 (-1100 3550)(-1100 3500);
WIRE 16 -1 (-500 3650)(-500 3975);
WIRE 16 -1 (-500 3475)(-500 3650);
WIRE 16 -1 (-700 3550)(-700 2900);
WIRE 16 -1 (-700 2900)(-1600 2900);
WIRE 16 -1 (-2619 2326)(-2619 2327);
WIRE 16 -1 (-3250 3200)(-3250 2875);
WIRE 16 -1 (-3250 3200)(-3150 3200);
WIRE 16 -1 (-3475 3200)(-3250 3200);
WIRE 16 -1 (-3250 2875)(-3475 2875);
WIRE 16 -1 (-3150 2400)(-3150 3200);
WIRE 16 -1 (-3150 3200)(-3000 3200);
WIRE 16 -1 (-3000 3200)(-3000 2900);
WIRE 16 -1 (-3150 2400)(-2700 2400);
WIRE 16 -1 (-3000 2900)(-1800 2900);
FORCEPROP 2 LAST SIG_NAME PVDD18_S5_P0_FB_RC
J 0
(-2860 2910);
DISPLAY 0.489362 (-2860 2910);
FORCEPROP 2 LASTPROP $XRERR UNIQUE?
J 0
(-3100 2910);
DISPLAY 0.638298 (-3100 2910);
PAINT MONO (-3100 2910);
DISPLAY INVISIBLE (-3100 2910);
WIRE 16 -1 (-3607 2297)(-3607 2298);
WIRE 16 -1 (-5350 3650)(-4475 3650);
FORCEPROP 2 LAST SIG_NAME SW_PVDD18_S5_P0_SW
J 0
(-5245 3667);
DISPLAY 0.489362 (-5245 3667);
FORCEPROP 2 LASTPROP $XRERR UNIQUE?
J 0
(-5485 3667);
DISPLAY 0.638298 (-5485 3667);
PAINT MONO (-5485 3667);
DISPLAY INVISIBLE (-5485 3667);
WIRE 16 -1 (-4475 3650)(-3675 3650);
WIRE 16 -1 (-4475 3700)(-4475 3650);
WIRE 16 -1 (-5350 3050)(-4350 3050);
FORCEPROP 2 LAST SIG_NAME PVDD18_S5_P0_RGND
J 0
(-5260 3060);
DISPLAY 0.489362 (-5260 3060);
FORCEPROP 2 LASTPROP $XRERR UNIQUE?
J 0
(-5500 3060);
DISPLAY 0.638298 (-5500 3060);
PAINT MONO (-5500 3060);
DISPLAY INVISIBLE (-5500 3060);
WIRE 16 -1 (-4350 3050)(-4350 2950);
WIRE 16 -1 (-4475 2950)(-4350 2950);
WIRE 16 -1 (-4350 2950)(-4350 2100);
WIRE 16 -1 (-4350 2100)(-4150 2100);
WIRE 16 -1 (-3575 2100)(-4150 2100);
WIRE 16 -1 (-4150 2575)(-4150 2100);
WIRE 16 -1 (-2700 2100)(-3575 2100);
WIRE 16 -1 (-3575 2100)(-3575 1950);
WIRE 16 -1 (-5000 2950)(-4675 2950);
WIRE 16 -1 (-5000 2875)(-5000 2950);
WIRE 16 -1 (-5000 2950)(-5350 2950);
FORCEPROP 2 LAST SIG_NAME PVDD18_S5_P0_REF
J 0
(-5260 2960);
DISPLAY 0.489362 (-5260 2960);
FORCEPROP 2 LASTPROP $XRERR UNIQUE?
J 0
(-5500 2960);
DISPLAY 0.638298 (-5500 2960);
PAINT MONO (-5500 2960);
DISPLAY INVISIBLE (-5500 2960);
WIRE 16 -1 (-5125 2575)(-5125 2800);
WIRE 16 -1 (-5125 2800)(-5125 2850);
WIRE 16 -1 (-5350 2800)(-5125 2800);
WIRE 16 -1 (-5125 2850)(-5350 2850);
WIRE 16 -1 (-6700 2725)(-6700 2850);
FORCEPROP 2 LAST SIG_NAME PVDD18_S5_P0_CS
J 0
(-6560 2875);
DISPLAY 0.489362 (-6560 2875);
FORCEPROP 2 LASTPROP $XRERR UNIQUE?
J 0
(-6800 2875);
DISPLAY 0.638298 (-6800 2875);
PAINT MONO (-6800 2875);
DISPLAY INVISIBLE (-6800 2875);
WIRE 16 -1 (-6700 2850)(-6150 2850);
WIRE 16 -1 (-8575 3650)(-6150 3650);
WIRE 16 -1 (-8575 3650)(-8575 3550);
WIRE 16 -1 (-8575 3650)(-8800 3650);
FORCEPROP 2 LAST SIG_NAME PVDD18_S5_P0_EN
J 0
(-8760 3660);
DISPLAY 0.489362 (-8760 3660);
WIRE 16 -1 (-9146 4595)(-9146 4425);
WIRE 16 -1 (-8975 4425)(-9146 4425);
WIRE 16 -1 (-4475 3900)(-4475 3950);
WIRE 16 -1 (-5350 3950)(-4475 3950);
FORCEPROP 2 LAST SIG_NAME SW_PVDD18_S5_P0_BST
J 0
(-5260 3975);
DISPLAY 0.489362 (-5260 3975);
FORCEPROP 2 LASTPROP $XRERR UNIQUE?
J 0
(-5500 3975);
DISPLAY 0.638298 (-5500 3975);
PAINT MONO (-5500 3975);
DISPLAY INVISIBLE (-5500 3975);
WIRE 16 -1 (-5350 3200)(-4150 3200);
FORCEPROP 2 LAST SIG_NAME PVDD18_S5_P0_FB
J 0
(-5251 3214);
DISPLAY 0.489362 (-5251 3214);
FORCEPROP 2 LASTPROP $XRERR UNIQUE?
J 0
(-5491 3214);
DISPLAY 0.638298 (-5491 3214);
PAINT MONO (-5491 3214);
DISPLAY INVISIBLE (-5491 3214);
WIRE 16 -1 (-3875 3200)(-4150 3200);
WIRE 16 -1 (-4150 2775)(-4150 3200);
WIRE 16 -1 (-3675 3200)(-3875 3200);
WIRE 16 -1 (-3875 3200)(-3875 2875);
WIRE 16 -1 (-3675 2875)(-3875 2875);
WIRE 16 -1 (-6325 4100)(-6150 4100);
WIRE 16 -1 (-6325 4150)(-6325 4100);
WIRE 16 -1 (-6325 4150)(-6150 4150);
WIRE 16 -1 (-6325 4425)(-6325 4150);
WIRE 16 -1 (-6725 4425)(-6325 4425);
WIRE 16 -1 (-6725 4300)(-6725 4425);
WIRE 16 -1 (-7125 4425)(-6725 4425);
WIRE 16 -1 (-7125 4300)(-7125 4425);
WIRE 16 -1 (-7575 4425)(-7125 4425);
WIRE 16 -1 (-7575 4300)(-7575 4425);
WIRE 16 -1 (-7575 4425)(-7975 4425);
FORCEPROP 2 LAST SIG_NAME SW_P12V_STBY_PVDD18_S5_P0_FLT
J 0
(-7762 4448);
DISPLAY 0.489362 (-7762 4448);
FORCEPROP 2 LASTPROP $XRERR UNIQUE?
J 0
(-8002 4448);
DISPLAY 0.638298 (-8002 4448);
PAINT MONO (-8002 4448);
DISPLAY INVISIBLE (-8002 4448);
WIRE 16 -1 (-7975 4300)(-7975 4425);
WIRE 16 -1 (-8350 4425)(-7975 4425);
WIRE 16 -1 (-8350 4300)(-8350 4425);
WIRE 16 -1 (-8775 4425)(-8350 4425);
WIRE 16 -1 (-6725 4100)(-6725 3978);
WIRE 16 -1 (-6725 3978)(-7125 3978);
WIRE 16 -1 (-7125 4100)(-7125 3978);
WIRE 16 -1 (-7125 3978)(-7575 3978);
WIRE 16 -1 (-7575 4100)(-7575 3978);
WIRE 16 -1 (-7950 3978)(-7575 3978);
WIRE 16 -1 (-7950 3875)(-7950 3978);
WIRE 16 -1 (-7975 3978)(-7950 3978);
WIRE 16 -1 (-7975 4100)(-7975 3978);
WIRE 16 -1 (-8350 3978)(-7975 3978);
WIRE 16 -1 (-8350 4100)(-8350 3978);
WIRE 16 -1 (-6975 3450)(-6150 3450);
FORCEPROP 2 LAST SIG_NAME PVDD18_S5_P0_MODE
J 0
(-6810 3460);
DISPLAY 0.489362 (-6810 3460);
FORCEPROP 2 LASTPROP $XRERR UNIQUE?
J 0
(-7050 3460);
DISPLAY 0.638298 (-7050 3460);
PAINT MONO (-7050 3460);
DISPLAY INVISIBLE (-7050 3460);
WIRE 16 -1 (-6150 3200)(-7025 3200);
FORCEPROP 2 LAST SIG_NAME PVDD18_S5_P0_VCC
J 0
(-6610 3210);
DISPLAY 0.489362 (-6610 3210);
FORCEPROP 2 LASTPROP $XRERR UNIQUE?
J 0
(-6850 3210);
DISPLAY 0.638298 (-6850 3210);
PAINT MONO (-6850 3210);
DISPLAY INVISIBLE (-6850 3210);
WIRE 16 -1 (-7025 2850)(-7025 3200);
WIRE 16 -1 (-7575 2850)(-7025 2850);
WIRE 16 -1 (-7575 2950)(-7575 2850);
WIRE 16 -1 (-7575 2725)(-7575 2850);
WIRE 17 273 (-9025 1825)(-6850 1825);
WIRE 17 273 (-9025 2225)(-9025 1825);
WIRE 17 273 (-6850 2225)(-6850 1825);
WIRE 17 273 (-9025 2225)(-6850 2225);
WIRE 17 273 (-9025 1075)(-6850 1075);
WIRE 17 273 (-9025 1675)(-9025 1075);
WIRE 17 273 (-6850 1675)(-6850 1075);
WIRE 17 273 (-9025 1675)(-6850 1675);
DOT 1 (-4700 4150);
DOT 1 (-2475 3150);
DOT 1 (-8575 3650);
DOT 1 (-8350 4425);
DOT 1 (-7575 2850);
DOT 1 (-7975 3978);
DOT 1 (-7950 3978);
DOT 1 (-7575 3978);
DOT 1 (-5125 2800);
DOT 1 (-5000 2950);
DOT 1 (-4150 2100);
DOT 1 (-4350 2950);
DOT 1 (-4150 3200);
DOT 1 (-4475 3650);
DOT 1 (-7975 4425);
DOT 1 (-7575 4425);
DOT 1 (-7125 4425);
DOT 1 (-6725 4425);
DOT 1 (-6325 4150);
DOT 1 (-3575 2100);
DOT 1 (-3875 3200);
DOT 1 (-3250 3200);
DOT 1 (-3150 3200);
DOT 1 (-2925 3650);
DOT 1 (-2275 3150);
DOT 1 (-2275 3650);
DOT 1 (-2475 3650);
DOT 1 (-2025 3150);
DOT 1 (-1700 3150);
DOT 1 (-1700 3650);
DOT 1 (-2025 3650);
DOT 1 (-1425 3150);
DOT 1 (-1100 3150);
DOT 1 (-1100 3550);
DOT 1 (-1425 3650);
DOT 1 (-1100 3650);
DOT 1 (-500 3650);
DOT 1 (-7125 3978);
FORCENOTE
3RD=CX000220000
(-9075 4200) 0;
DISPLAY LEFT (-9075 4200);
DISPLAY 0.808511 (-9075 4200);
PAINT WHITE (-9075 4200);
FORCENOTE
2ND=CX220Z06Z00
(-9075 4250) 0;
DISPLAY LEFT (-9075 4250);
DISPLAY 0.808511 (-9075 4250);
PAINT WHITE (-9075 4250);
FORCENOTE
VOUT=0.6(1+RA/RB)=1.8V
(-5725 1825) 0;
DISPLAY LEFT (-5725 1825);
DISPLAY 2.000000 (-5725 1825);
PAINT WHITE (-5725 1825);
FORCENOTE
NEAR CPU SIDE
(-3100 1675) 0;
DISPLAY LEFT (-3100 1675);
DISPLAY 1.021277 (-3100 1675);
PAINT GREEN (-3100 1675);
FORCENOTE
2ND=CV-10M0MZ02
(-3400 3725) 0;
DISPLAY LEFT (-3400 3725);
DISPLAY 0.638298 (-3400 3725);
PAINT WHITE (-3400 3725);
FORCENOTE
DCR=10M OHM
(-3400 3775) 0;
DISPLAY LEFT (-3400 3775);
DISPLAY 0.638298 (-3400 3775);
PAINT WHITE (-3400 3775);
FORCENOTE
ISAT:20A@100C
(-3400 3875) 0;
DISPLAY LEFT (-3400 3875);
DISPLAY 0.638298 (-3400 3875);
PAINT WHITE (-3400 3875);
FORCENOTE
PCMC063T-1R0MN
(-3400 3925) 0;
DISPLAY LEFT (-3400 3925);
DISPLAY 0.638298 (-3400 3925);
PAINT WHITE (-3400 3925);
FORCENOTE
6.6*6.6*3.0
(-3400 3825) 0;
DISPLAY LEFT (-3400 3825);
DISPLAY 0.638298 (-3400 3825);
PAINT WHITE (-3400 3825);
FORCENOTE
DIFFERENTIAL PAIR
(-1725 1875) 0;
DISPLAY LEFT (-1725 1875);
DISPLAY 1.021277 (-1725 1875);
PAINT WHITE (-1725 1875);
FORCENOTE
TRACE WIDTH = 10MIL
(-1725 1800) 0;
DISPLAY LEFT (-1725 1800);
DISPLAY 1.021277 (-1725 1800);
PAINT WHITE (-1725 1800);
FORCENOTE
TRACE SPACING = 5MIL
(-1725 1725) 0;
DISPLAY LEFT (-1725 1725);
DISPLAY 1.021277 (-1725 1725);
PAINT WHITE (-1725 1725);
FORCENOTE
DCR=5M OHM
(-9075 4300) 0;
DISPLAY LEFT (-9075 4300);
DISPLAY 0.808511 (-9075 4300);
PAINT WHITE (-9075 4300);
FORCENOTE
IRATED=5A@125C
(-9075 4350) 0;
DISPLAY LEFT (-9075 4350);
DISPLAY 0.808511 (-9075 4350);
PAINT WHITE (-9075 4350);
FORCENOTE
RB
(-4275 2650) 0;
DISPLAY LEFT (-4275 2650);
DISPLAY 1.021277 (-4275 2650);
PAINT WHITE (-4275 2650);
FORCENOTE
FCCM
(-8725 3025) 0;
DISPLAY LEFT (-8725 3025);
DISPLAY 1.276596 (-8725 3025);
PAINT WHITE (-8725 3025);
FORCENOTE
FSW=600KHZ
(-8725 2925) 0;
DISPLAY LEFT (-8725 2925);
DISPLAY 1.276596 (-8725 2925);
PAINT WHITE (-8725 2925);
FORCENOTE
RA
(-3625 3300) 0;
DISPLAY LEFT (-3625 3300);
DISPLAY 1.021277 (-3625 3300);
PAINT WHITE (-3625 3300);
FORCENOTE
5.0*5.8
(-1450 3050) 0;
DISPLAY LEFT (-1450 3050);
DISPLAY 0.510638 (-1450 3050);
FORCENOTE
ESR=10M OHM
(-1450 3100) 0;
DISPLAY LEFT (-1450 3100);
DISPLAY 0.510638 (-1450 3100);
FORCENOTE
EDC=12A
(-1650 6075) 0;
DISPLAY LEFT (-1650 6075);
DISPLAY 0.936170 (-1650 6075);
PAINT WHITE (-1650 6075);
FORCENOTE
EFFICIENCY > 90% @TDC
(-1650 5700) 0;
DISPLAY LEFT (-1650 5700);
DISPLAY 0.936170 (-1650 5700);
PAINT WHITE (-1650 5700);
FORCENOTE
WORK FREQUENCY=600KHZ
(-1650 5775) 0;
DISPLAY LEFT (-1650 5775);
DISPLAY 0.936170 (-1650 5775);
PAINT WHITE (-1650 5775);
FORCENOTE
LOAD RELEASE=1.5A
(-1650 5850) 0;
DISPLAY LEFT (-1650 5850);
DISPLAY 0.936170 (-1650 5850);
PAINT WHITE (-1650 5850);
FORCENOTE
LOAD STEP=1.5A
(-1650 5925) 0;
DISPLAY LEFT (-1650 5925);
DISPLAY 0.936170 (-1650 5925);
PAINT WHITE (-1650 5925);
FORCENOTE
OCP=15A (EDC*1.2)
(-1650 6000) 0;
DISPLAY LEFT (-1650 6000);
DISPLAY 0.936170 (-1650 6000);
PAINT WHITE (-1650 6000);
FORCENOTE
TDC=10A
(-1650 6150) 0;
DISPLAY LEFT (-1650 6150);
DISPLAY 0.936170 (-1650 6150);
PAINT WHITE (-1650 6150);
FORCENOTE
AC TOLERANCE=+/-30MV
(-1650 6225) 0;
DISPLAY LEFT (-1650 6225);
DISPLAY 0.936170 (-1650 6225);
PAINT WHITE (-1650 6225);
FORCENOTE
OUTPUT VOLTAGE=1.8V+/-40MV
(-1650 6375) 0;
DISPLAY LEFT (-1650 6375);
DISPLAY 0.936170 (-1650 6375);
PAINT WHITE (-1650 6375);
FORCENOTE
PVDD18_S5_P0 SPECFICATION
(-1650 6500) 0;
DISPLAY LEFT (-1650 6500);
DISPLAY 1.276596 (-1650 6500);
PAINT WHITE (-1650 6500);
FORCENOTE
RIPPLE=+/-20MV
(-1650 6300) 0;
DISPLAY LEFT (-1650 6300);
DISPLAY 0.936170 (-1650 6300);
PAINT WHITE (-1650 6300);
FORCENOTE
MAIN SOURCE:
(-8950 1425) 0;
DISPLAY LEFT (-8950 1425);
DISPLAY 1.021277 (-8950 1425);
PAINT WHITE (-8950 1425);
FORCENOTE
PVDD18_S5_P0
(-6175 5550) 0;
DISPLAY LEFT (-6175 5550);
DISPLAY 3.148936 (-6175 5550);
PAINT WHITE (-6175 5550);
FORCENOTE
BOM NOTE
(-8950 2125) 0;
DISPLAY LEFT (-8950 2125);
DISPLAY 1.276596 (-8950 2125);
PAINT WHITE (-8950 2125);
FORCENOTE
BOM CHANGE
(-8950 1575) 0;
DISPLAY LEFT (-8950 1575);
DISPLAY 1.276596 (-8950 1575);
PAINT WHITE (-8950 1575);
FORCENOTE
2ND SOURCE:AL000548007/TPS548B28RWWR
(-8950 1875) 0;
DISPLAY LEFT (-8950 1875);
DISPLAY 1.021277 (-8950 1875);
PAINT WHITE (-8950 1875);
FORCENOTE
MAIN SOURCE:AL008633005/MPQ8633BGLE-C807-Z
(-8950 1975) 0;
DISPLAY LEFT (-8950 1975);
DISPLAY 1.021277 (-8950 1975);
PAINT WHITE (-8950 1975);
FORCENOTE
PC259 CHANGE TO CH13306JB14
(-8425 1225) 0;
DISPLAY LEFT (-8425 1225);
DISPLAY 1.021277 (-8425 1225);
PAINT WHITE (-8425 1225);
FORCENOTE
2ND SOURCE:PC237 CHANGE TO CH5104KEB02
(-8950 1325) 0;
DISPLAY LEFT (-8950 1325);
DISPLAY 1.021277 (-8950 1325);
PAINT WHITE (-8950 1325);
QUIT
